FILE_TYPE = MACRO_DRAWING;
SET COLOR_WIRE YELLOW;
SET COLOR_PROP MONO;
SET COLOR_DOT WHITE;
SET COLOR_ARC YELLOW;
SET COLOR_BODY GREEN;
SET COLOR_NOTE MONO;
SET PROP_DISPLAY VALUE;
SET PAGE_NUMBER P214;
FORCEADD RES..1
(-750 1050);
FORCEPROP 1 LAST MATERIAL CHIP
J 0
(-700 925);
DISPLAY 0.617021 (-700 925);
PAINT SKYBLUE (-700 925);
FORCEPROP 1 LAST PART_NUMBER G21796-017
J 0
(-900 875);
DISPLAY 0.617021 (-900 875);
PAINT BLUE (-900 875);
FORCEPROP 1 LAST TOLERANCE 1%
J 0
(-925 975);
DISPLAY 0.617021 (-925 975);
PAINT SKYBLUE (-925 975);
FORCEPROP 1 LAST WATTAGE 1/16W
J 2
(-725 925);
DISPLAY 0.617021 (-725 925);
PAINT SKYBLUE (-725 925);
FORCEPROP 1 LAST VALUE 100.0
J 2
(-750 975);
DISPLAY 0.617021 (-750 975);
PAINT SKYBLUE (-750 975);
FORCEPROP 1 LAST PACK_TYPE 0402
J 0
(-700 975);
DISPLAY 0.617021 (-700 975);
PAINT SKYBLUE (-700 975);
FORCEPROP 1 LASTPIN (-850 1050) $PN 1
J 0
(-838 1062);
DISPLAY 0.617021 (-838 1062);
PAINT WHITE (-838 1062);
FORCEPROP 1 LAST LOCATION R3D28
J 0
(-800 1100);
DISPLAY 0.617021 (-800 1100);
PAINT AQUA (-800 1100);
FORCEPROP 1 LASTPIN (-650 1050) $PN 2
J 0
(-688 1062);
DISPLAY 0.617021 (-688 1062);
PAINT WHITE (-688 1062);
FORCEPROP 2 LAST ROOM PVCCIO_CPU1
J 0
(-800 1200);
DISPLAY 0.723404 (-800 1200);
PAINT ORANGE (-800 1200);
DISPLAY INVISIBLE (-800 1200);
FORCEPROP 1 LAST PATH I101
J 0
(-800 1200);
DISPLAY 0.978723 (-800 1200);
PAINT WHITE (-800 1200);
DISPLAY INVISIBLE (-800 1200);
FORCEPROP 2 LAST SEC 1
J 0
(-800 1246);
DISPLAY 0.680851 (-800 1246);
PAINT MONO (-800 1246);
DISPLAY INVISIBLE (-800 1246);
FORCEPROP 0 LAST BOM_COST PROC_VRD_VCCIO_CPU1
J 0
(-800 1150);
DISPLAY 0.723404 (-800 1150);
PAINT ORANGE (-800 1150);
DISPLAY INVISIBLE (-800 1150);
FORCEPROP 2 LAST CDS_LOCATION R3D28
J 0
(-800 1100);
DISPLAY 0.617021 (-800 1100);
PAINT AQUA (-800 1100);
DISPLAY INVISIBLE (-800 1100);
FORCEPROP 2 LAST SEC_TYPE 0402
J 0
(-800 1246);
DISPLAY 1.021277 (-800 1246);
PAINT ORANGE (-800 1246);
DISPLAY INVISIBLE (-800 1246);
FORCEPROP 2 LAST CDS_LIB mstr_discrete
J 0
(-750 1050);
PAINT ORANGE (-750 1050);
DISPLAY INVISIBLE (-750 1050);
FORCEADD GND..1
(-500 825);
FORCEPROP 3 LASTPIN (-500 875) SIG_NAME GND\g
J 0
(-490 885);
DISPLAY 0.659574 (-490 885);
PAINT MONO (-490 885);
DISPLAY INVISIBLE (-490 885);
FORCEPROP 2 LAST ROOM PVCCIO_CPU0
J 0
(-800 900);
DISPLAY 0.723404 (-800 900);
PAINT ORANGE (-800 900);
DISPLAY INVISIBLE (-800 900);
FORCEPROP 2 LAST BOM_COST MEM_VRD_PVCCIO_CPU0
J 0
(-1000 900);
DISPLAY 0.723404 (-1000 900);
PAINT ORANGE (-1000 900);
DISPLAY INVISIBLE (-1000 900);
FORCEPROP 1 LAST VOLTAGE 0
J 0
(-500 825);
DISPLAY 0.723404 (-500 825);
PAINT SKYBLUE (-500 825);
DISPLAY INVISIBLE (-500 825);
FORCEPROP 1 LAST PATH I102
J 0
(-425 825);
DISPLAY 0.872340 (-425 825);
PAINT AQUA (-425 825);
DISPLAY INVISIBLE (-425 825);
FORCEPROP 2 LAST CDS_LIB mstr_symbols
J 0
(-500 825);
PAINT ORANGE (-500 825);
DISPLAY INVISIBLE (-500 825);
FORCEPROP 1 LAST SIZE 1B
J 0
(-425 775);
DISPLAY 0.638298 (-425 775);
PAINT GREEN (-425 775);
DISPLAY INVISIBLE (-425 775);
FORCEPROP 1 LAST BODY_TYPE PLUMBING
J 0
(-545 782);
DISPLAY 0.340426 (-545 782);
PAINT GREEN (-545 782);
DISPLAY INVISIBLE (-545 782);
FORCEPROP 1 LAST HDL_POWER GND
J 0
(-500 975);
DISPLAY 0.638298 (-500 975);
PAINT GREEN (-500 975);
DISPLAY INVISIBLE (-500 975);
FORCEADD OFFPAGE..2
(-275 1300);
FORCEPROP 2 LAST $XR0 213 
J 0
(-86 1300);
DISPLAY 0.638298 (-86 1300);
PAINT MONO (-86 1300);
FORCEPROP 2 LAST CDS_LIB mstr_standard
J 0
(-275 1300);
PAINT ORANGE (-275 1300);
DISPLAY INVISIBLE (-275 1300);
FORCEPROP 2 LAST ROOM PVCCIO_CPU0
J 0
(0 1325);
DISPLAY 0.617021 (0 1325);
PAINT ORANGE (0 1325);
DISPLAY INVISIBLE (0 1325);
FORCEPROP 2 LAST PATH I103
J 0
(-75 1350);
DISPLAY 1.021277 (-75 1350);
PAINT ORANGE (-75 1350);
DISPLAY INVISIBLE (-75 1350);
FORCEPROP 1 LAST OFFPAGE TRUE
J 0
(50 1175);
DISPLAY 0.872340 (50 1175);
PAINT GREEN (50 1175);
DISPLAY INVISIBLE (50 1175);
FORCEPROP 1 LAST COMMENT_BODY TRUE
J 0
(-320 1205);
DISPLAY 0.872340 (-320 1205);
PAINT GREEN (-320 1205);
DISPLAY INVISIBLE (-320 1205);
FORCEADD RES..1
(-750 2250);
FORCEPROP 1 LAST LOCATION R3E1
J 0
(-800 2300);
DISPLAY 0.617021 (-800 2300);
PAINT AQUA (-800 2300);
FORCEPROP 1 LAST PART_NUMBER G21796-017
J 0
(-900 2075);
DISPLAY 0.617021 (-900 2075);
PAINT BLUE (-900 2075);
FORCEPROP 1 LAST WATTAGE 1/16W
J 2
(-725 2125);
DISPLAY 0.617021 (-725 2125);
PAINT SKYBLUE (-725 2125);
FORCEPROP 1 LAST PACK_TYPE 0402
J 0
(-700 2175);
DISPLAY 0.617021 (-700 2175);
PAINT SKYBLUE (-700 2175);
FORCEPROP 1 LASTPIN (-650 2250) $PN 2
J 0
(-688 2262);
DISPLAY 0.617021 (-688 2262);
PAINT WHITE (-688 2262);
FORCEPROP 1 LAST MATERIAL CHIP
J 0
(-700 2125);
DISPLAY 0.617021 (-700 2125);
PAINT SKYBLUE (-700 2125);
FORCEPROP 1 LAST TOLERANCE 1%
J 0
(-925 2175);
DISPLAY 0.617021 (-925 2175);
PAINT SKYBLUE (-925 2175);
FORCEPROP 1 LAST VALUE 100.0
J 2
(-750 2175);
DISPLAY 0.617021 (-750 2175);
PAINT SKYBLUE (-750 2175);
FORCEPROP 1 LASTPIN (-850 2250) $PN 1
J 0
(-838 2262);
DISPLAY 0.617021 (-838 2262);
PAINT WHITE (-838 2262);
FORCEPROP 2 LAST CDS_LOCATION R3E1
J 0
(-800 2300);
DISPLAY 0.617021 (-800 2300);
PAINT AQUA (-800 2300);
DISPLAY INVISIBLE (-800 2300);
FORCEPROP 2 LAST ROOM PVCCIO_CPU1
J 0
(-800 2400);
DISPLAY 0.723404 (-800 2400);
PAINT ORANGE (-800 2400);
DISPLAY INVISIBLE (-800 2400);
FORCEPROP 1 LAST PATH I105
J 0
(-800 2400);
DISPLAY 0.978723 (-800 2400);
PAINT WHITE (-800 2400);
DISPLAY INVISIBLE (-800 2400);
FORCEPROP 2 LAST SEC 1
J 0
(-800 2446);
DISPLAY 0.680851 (-800 2446);
PAINT MONO (-800 2446);
DISPLAY INVISIBLE (-800 2446);
FORCEPROP 2 LAST SEC_TYPE 0402
J 0
(-800 2446);
DISPLAY 1.021277 (-800 2446);
PAINT ORANGE (-800 2446);
DISPLAY INVISIBLE (-800 2446);
FORCEPROP 0 LAST BOM_COST PROC_VRD_VCCIO_CPU1
J 0
(-800 2350);
DISPLAY 0.723404 (-800 2350);
PAINT ORANGE (-800 2350);
DISPLAY INVISIBLE (-800 2350);
FORCEPROP 2 LAST CDS_LIB mstr_discrete
J 0
(-750 2250);
PAINT ORANGE (-750 2250);
DISPLAY INVISIBLE (-750 2250);
FORCEADD OFFPAGE..2
(-300 1750);
FORCEPROP 2 LAST $XR0 213 
J 0
(-111 1750);
DISPLAY 0.638298 (-111 1750);
PAINT MONO (-111 1750);
FORCEPROP 2 LAST CDS_LIB mstr_standard
J 0
(-300 1750);
PAINT ORANGE (-300 1750);
DISPLAY INVISIBLE (-300 1750);
FORCEPROP 2 LAST ROOM PVCCIO_CPU0
J 0
(-25 1775);
DISPLAY 0.617021 (-25 1775);
PAINT ORANGE (-25 1775);
DISPLAY INVISIBLE (-25 1775);
FORCEPROP 2 LAST PATH I106
J 0
(-100 1800);
DISPLAY 1.021277 (-100 1800);
PAINT ORANGE (-100 1800);
DISPLAY INVISIBLE (-100 1800);
FORCEPROP 1 LAST OFFPAGE TRUE
J 0
(25 1625);
DISPLAY 0.872340 (25 1625);
PAINT GREEN (25 1625);
DISPLAY INVISIBLE (25 1625);
FORCEPROP 1 LAST COMMENT_BODY TRUE
J 0
(-345 1655);
DISPLAY 0.872340 (-345 1655);
PAINT GREEN (-345 1655);
DISPLAY INVISIBLE (-345 1655);
FORCEADD PVCCIO_CPU1..1
(-500 2525);
FORCEPROP 3 LASTPIN (-500 2475) SIG_NAME PVCCIO_CPU1\g
J 0
(-490 2485);
DISPLAY 0.659574 (-490 2485);
PAINT MONO (-490 2485);
DISPLAY INVISIBLE (-490 2485);
FORCEPROP 2 LAST CDS_LIB mstr_symbols
J 0
(-500 2525);
PAINT ORANGE (-500 2525);
DISPLAY INVISIBLE (-500 2525);
FORCEPROP 1 LAST PATH I107
J 0
(-450 2550);
DISPLAY 0.872340 (-450 2550);
PAINT AQUA (-450 2550);
DISPLAY INVISIBLE (-450 2550);
FORCEPROP 1 LAST VOLTAGE 1.1V
J 0
(-545 2482);
DISPLAY 0.340426 (-545 2482);
PAINT SKYBLUE (-545 2482);
DISPLAY INVISIBLE (-545 2482);
FORCEPROP 1 LAST BODY_TYPE PLUMBING
J 0
(-545 2482);
DISPLAY 0.340426 (-545 2482);
PAINT GREEN (-545 2482);
DISPLAY INVISIBLE (-545 2482);
FORCEPROP 1 LAST HDL_POWER PVCCIO_CPU1
J 1
(-500 2575);
DISPLAY 0.872340 (-500 2575);
PAINT GREEN (-500 2575);
DISPLAY INVISIBLE (-500 2575);
FORCEADD CAP_A..1
(3650 3450);
FORCEPROP 0 LAST GROUP PWR_MLCC_CAP
J 0
(3706 3187);
DISPLAY 0.638298 (3706 3187);
PAINT BROWN (3706 3187);
DISPLAY BOTH (3706 3187);
FORCEPROP 1 LAST VALUE 22.0UF
J 0
(3700 3525);
DISPLAY 0.617021 (3700 3525);
PAINT SKYBLUE (3700 3525);
FORCEPROP 1 LAST TOLERANCE 20%
J 0
(3700 3425);
DISPLAY 0.617021 (3700 3425);
PAINT SKYBLUE (3700 3425);
FORCEPROP 1 LAST MATERIAL X6S
J 0
(3700 3375);
DISPLAY 0.617021 (3700 3375);
PAINT SKYBLUE (3700 3375);
FORCEPROP 1 LAST PART_NUMBER E15431-004
J 0
(3700 3325);
DISPLAY 0.617021 (3700 3325);
PAINT BLUE (3700 3325);
FORCEPROP 1 LAST PACK_TYPE 0603V
J 0
(3700 3275);
DISPLAY 0.617021 (3700 3275);
PAINT SKYBLUE (3700 3275);
FORCEPROP 1 LAST VOLTAGE 4V
J 0
(3700 3475);
DISPLAY 0.617021 (3700 3475);
PAINT SKYBLUE (3700 3475);
FORCEPROP 1 LAST LOCATION C3E1
J 0
(3696 3572);
DISPLAY 0.617021 (3696 3572);
PAINT AQUA (3696 3572);
FORCEPROP 1 LASTPIN (3650 3350) $PN 2
J 0
(3660 3330);
DISPLAY 0.787234 (3660 3330);
PAINT ORANGE (3660 3330);
FORCEPROP 1 LASTPIN (3650 3550) $PN 1
J 0
(3660 3530);
DISPLAY 0.787234 (3660 3530);
PAINT ORANGE (3660 3530);
FORCEPROP 2 LAST ROOM PVCCIO_CPU1
J 0
(3700 3600);
DISPLAY 0.723404 (3700 3600);
PAINT ORANGE (3700 3600);
DISPLAY INVISIBLE (3700 3600);
FORCEPROP 1 LAST PATH I108
J 0
(3700 3600);
DISPLAY 0.978723 (3700 3600);
PAINT WHITE (3700 3600);
DISPLAY INVISIBLE (3700 3600);
FORCEPROP 2 LAST BOM_COST PROC_VRD_PVCCIO_CPU1
J 0
(3700 3600);
DISPLAY 0.723404 (3700 3600);
PAINT ORANGE (3700 3600);
DISPLAY INVISIBLE (3700 3600);
FORCEPROP 2 LAST REUSE_ID 281
J 0
(3700 3650);
DISPLAY 0.723404 (3700 3650);
PAINT MONO (3700 3650);
DISPLAY INVISIBLE (3700 3650);
FORCEPROP 2 LAST CDS_LOCATION C3E1
J 0
(3471 3547);
DISPLAY 0.617021 (3471 3547);
PAINT AQUA (3471 3547);
DISPLAY INVISIBLE (3471 3547);
FORCEPROP 2 LAST CDS_LIB dev_discrete
J 0
(3650 3450);
PAINT ORANGE (3650 3450);
DISPLAY INVISIBLE (3650 3450);
FORCEPROP 2 LAST SEC 1
J 0
(3700 3650);
PAINT MONO (3700 3650);
DISPLAY INVISIBLE (3700 3650);
FORCEPROP 2 LAST SEC_TYPE 0603V
J 0
(3700 3650);
DISPLAY 1.021277 (3700 3650);
PAINT ORANGE (3700 3650);
DISPLAY INVISIBLE (3700 3650);
FORCEADD RES..2
(3975 3425);
FORCEPROP 1 LAST LOCATION R7R1
J 0
(4020 3550);
DISPLAY 0.617021 (4020 3550);
PAINT AQUA (4020 3550);
FORCEPROP 1 LAST VALUE 51.1
J 0
(4020 3500);
DISPLAY 0.617021 (4020 3500);
PAINT SKYBLUE (4020 3500);
FORCEPROP 1 LASTPIN (3975 3525) $PN 1
J 0
(3980 3487);
DISPLAY 0.787234 (3980 3487);
PAINT ORANGE (3980 3487);
FORCEPROP 1 LAST TOLERANCE 1.0%
J 0
(4020 3450);
DISPLAY 0.617021 (4020 3450);
PAINT SKYBLUE (4020 3450);
FORCEPROP 1 LAST WATTAGE 1/16W
J 0
(4015 3400);
DISPLAY 0.617021 (4015 3400);
PAINT SKYBLUE (4015 3400);
FORCEPROP 1 LAST MATERIAL CHIP
J 0
(4015 3350);
DISPLAY 0.617021 (4015 3350);
PAINT SKYBLUE (4015 3350);
FORCEPROP 1 LASTPIN (3975 3325) $PN 2
J 0
(3980 3335);
DISPLAY 0.787234 (3980 3335);
PAINT ORANGE (3980 3335);
FORCEPROP 1 LAST PART_NUMBER G21796-208
J 0
(4015 3300);
DISPLAY 0.617021 (4015 3300);
PAINT BLUE (4015 3300);
FORCEPROP 1 LAST PACK_TYPE 0402
J 0
(4015 3250);
DISPLAY 0.617021 (4015 3250);
PAINT SKYBLUE (4015 3250);
FORCEPROP 2 LAST CDS_LIB mstr_discrete
J 0
(3975 3425);
PAINT ORANGE (3975 3425);
DISPLAY INVISIBLE (3975 3425);
FORCEPROP 2 LAST CDS_LOCATION R7R1
J 0
(4020 3550);
DISPLAY 0.617021 (4020 3550);
PAINT AQUA (4020 3550);
DISPLAY INVISIBLE (4020 3550);
FORCEPROP 1 LAST PATH I109
J 0
(4025 3600);
DISPLAY 0.978723 (4025 3600);
PAINT WHITE (4025 3600);
DISPLAY INVISIBLE (4025 3600);
FORCEPROP 2 LAST SEC 1
J 0
(4025 3650);
PAINT MONO (4025 3650);
DISPLAY INVISIBLE (4025 3650);
FORCEPROP 2 LAST SEC_TYPE 0402
J 0
(4025 3650);
DISPLAY 1.021277 (4025 3650);
PAINT ORANGE (4025 3650);
DISPLAY INVISIBLE (4025 3650);
FORCEADD IR354XX..1
(1075 3925);
FORCEPROP 2 LASTPIN (575 4425) $PN 30
J 2
(565 4435);
DISPLAY 0.617021 (565 4435);
PAINT ORANGE (565 4435);
FORCEPROP 2 LASTPIN (575 3725) $PN 39
J 2
(565 3735);
DISPLAY 0.617021 (565 3735);
PAINT ORANGE (565 3735);
FORCEPROP 2 LASTPIN (575 3925) $PN 6
J 2
(565 3935);
DISPLAY 0.617021 (565 3935);
PAINT ORANGE (565 3935);
FORCEPROP 2 LASTPIN (575 4075) $PN 1
J 2
(565 4085);
DISPLAY 0.617021 (565 4085);
PAINT ORANGE (565 4085);
FORCEPROP 2 LASTPIN (575 4275) $PN 4
J 2
(565 4285);
DISPLAY 0.617021 (565 4285);
PAINT ORANGE (565 4285);
FORCEPROP 2 LASTPIN (575 4475) $PN 3
J 2
(565 4485);
DISPLAY 0.617021 (565 4485);
PAINT ORANGE (565 4485);
FORCEPROP 2 LASTPIN (575 4375) $PN 25
J 2
(565 4385);
DISPLAY 0.617021 (565 4385);
PAINT ORANGE (565 4385);
FORCEPROP 2 LASTPIN (1575 3425) $PN 7
J 0
(1585 3435);
DISPLAY 0.617021 (1585 3435);
PAINT ORANGE (1585 3435);
FORCEPROP 2 LASTPIN (1575 3375) $PN 5
J 0
(1585 3385);
DISPLAY 0.617021 (1585 3385);
PAINT ORANGE (1585 3385);
FORCEPROP 2 LASTPIN (1575 3475) $PN 40
J 0
(1585 3485);
DISPLAY 0.617021 (1585 3485);
PAINT ORANGE (1585 3485);
FORCEPROP 2 LASTPIN (1575 3525) $PN 2
J 0
(1585 3535);
DISPLAY 0.617021 (1585 3535);
PAINT ORANGE (1585 3535);
FORCEPROP 2 LASTPIN (1575 3625) $PN 10
J 0
(1585 3635);
DISPLAY 0.617021 (1585 3635);
PAINT ORANGE (1585 3635);
FORCEPROP 2 LASTPIN (1575 4275) $PN 37
J 0
(1585 4285);
DISPLAY 0.617021 (1585 4285);
PAINT ORANGE (1585 4285);
FORCEPROP 2 LAST NO_XNET_CONNECTION 1
J 0
(625 4775);
PAINT MONO (625 4775);
FORCEPROP 1 LAST MATERIAL IC
J 0
(625 4675);
DISPLAY 0.617021 (625 4675);
PAINT SKYBLUE (625 4675);
FORCEPROP 1 LAST LOCATION EU4E2
J 0
(625 4725);
DISPLAY 0.617021 (625 4725);
PAINT AQUA (625 4725);
FORCEPROP 1 LAST PART_NUMBER H73684-001
J 0
(725 3225);
DISPLAY 0.617021 (725 3225);
PAINT BLUE (725 3225);
FORCEPROP 2 LASTPIN (575 3975) $PN 41
J 2
(565 3985);
DISPLAY 0.617021 (565 3985);
PAINT ORANGE (565 3985);
FORCEPROP 2 LASTPIN (575 4175) $PN 35
J 2
(565 4185);
DISPLAY 0.617021 (565 4185);
PAINT ORANGE (565 4185);
FORCEPROP 2 LASTPIN (1575 3975) $PN 36
J 0
(1585 3985);
DISPLAY 0.617021 (1585 3985);
PAINT ORANGE (1585 3985);
FORCEPROP 2 LASTPIN (575 3575) $PN 32
J 2
(565 3585);
DISPLAY 0.617021 (565 3585);
PAINT ORANGE (565 3585);
FORCEPROP 2 LASTPIN (575 3625) $PN 33
J 2
(565 3635);
DISPLAY 0.617021 (565 3635);
PAINT ORANGE (565 3635);
FORCEPROP 2 LASTPIN (1575 4225) $PN 31
J 0
(1585 4235);
DISPLAY 0.617021 (1585 4235);
PAINT ORANGE (1585 4235);
FORCEPROP 2 LASTPIN (1575 4475) $PN 38
J 0
(1585 4485);
DISPLAY 0.617021 (1585 4485);
PAINT ORANGE (1585 4485);
FORCEPROP 2 LASTPIN (575 3825) $PN 34
J 2
(565 3835);
DISPLAY 0.617021 (565 3835);
PAINT ORANGE (565 3835);
FORCEPROP 2 LAST CDS_LIB mstr_discrete
J 0
(1075 3925);
PAINT ORANGE (1075 3925);
DISPLAY INVISIBLE (1075 3925);
FORCEPROP 2 LAST SEC_TYPE SM
J 0
(625 4775);
DISPLAY 1.021277 (625 4775);
PAINT ORANGE (625 4775);
DISPLAY INVISIBLE (625 4775);
FORCEPROP 2 LAST SEC 1
J 0
(625 4775);
DISPLAY 0.680851 (625 4775);
PAINT MONO (625 4775);
DISPLAY INVISIBLE (625 4775);
FORCEPROP 2 LAST CDS_LOCATION EU4E2
J 0
(625 4725);
PAINT GREEN (625 4725);
DISPLAY INVISIBLE (625 4725);
FORCEPROP 1 LAST PATH I126
J 0
(1075 4675);
PAINT GREEN (1075 4675);
DISPLAY INVISIBLE (1075 4675);
FORCEPROP 1 LAST PACK_TYPE SM
J 0
(625 4775);
PAINT SKYBLUE (625 4775);
DISPLAY INVISIBLE (625 4775);
FORCEPROP 1 LAST VALUE IR35412
J 1
(1075 4550);
DISPLAY 0.617021 (1075 4550);
PAINT SKYBLUE (1075 4550);
DISPLAY INVISIBLE (1075 4550);
FORCEADD RES..2
(3400 4075);
FORCEPROP 1 LAST LOCATION R4E21
J 0
(3445 4200);
DISPLAY 0.617021 (3445 4200);
PAINT AQUA (3445 4200);
FORCEPROP 1 LAST VALUE 68.1K
J 0
(3445 4150);
DISPLAY 0.617021 (3445 4150);
PAINT SKYBLUE (3445 4150);
FORCEPROP 1 LAST TOLERANCE 1%
J 0
(3445 4100);
DISPLAY 0.617021 (3445 4100);
PAINT SKYBLUE (3445 4100);
FORCEPROP 1 LAST WATTAGE 1/16W
J 0
(3440 4050);
DISPLAY 0.617021 (3440 4050);
PAINT SKYBLUE (3440 4050);
FORCEPROP 1 LAST MATERIAL EMPTY
J 0
(3440 4000);
DISPLAY 0.617021 (3440 4000);
PAINT RED (3440 4000);
FORCEPROP 1 LAST PACK_TYPE 0402
J 0
(3440 3900);
DISPLAY 0.617021 (3440 3900);
PAINT SKYBLUE (3440 3900);
FORCEPROP 1 LAST PART_NUMBER G21796-187
J 0
(3440 3950);
DISPLAY 0.617021 (3440 3950);
PAINT BLUE (3440 3950);
FORCEPROP 1 LASTPIN (3400 3975) $PN 2
J 0
(3405 3985);
DISPLAY 0.787234 (3405 3985);
PAINT ORANGE (3405 3985);
DISPLAY INVISIBLE (3405 3985);
FORCEPROP 2 LAST CDS_LIB mstr_discrete
J 0
(3400 4075);
PAINT ORANGE (3400 4075);
DISPLAY INVISIBLE (3400 4075);
FORCEPROP 1 LASTPIN (3400 4175) $PN 1
J 0
(3405 4137);
DISPLAY 0.787234 (3405 4137);
PAINT ORANGE (3405 4137);
DISPLAY INVISIBLE (3405 4137);
FORCEPROP 1 LAST PATH I127
J 0
(3450 4250);
DISPLAY 0.978723 (3450 4250);
PAINT WHITE (3450 4250);
DISPLAY INVISIBLE (3450 4250);
FORCEPROP 2 LAST CDS_SEC 1
J 0
(3450 4300);
PAINT MONO (3450 4300);
DISPLAY INVISIBLE (3450 4300);
FORCEPROP 2 LAST $SEC 1
J 0
(3450 4300);
PAINT MONO (3450 4300);
DISPLAY INVISIBLE (3450 4300);
FORCEADD GND..1
(3400 3875);
FORCEPROP 3 LASTPIN (3400 3925) SIG_NAME GND\g
J 0
(3410 3935);
DISPLAY 0.659574 (3410 3935);
PAINT MONO (3410 3935);
DISPLAY INVISIBLE (3410 3935);
FORCEPROP 1 LAST PATH I128
J 0
(3475 3875);
DISPLAY 0.872340 (3475 3875);
PAINT AQUA (3475 3875);
DISPLAY INVISIBLE (3475 3875);
FORCEPROP 1 LAST VOLTAGE 0
J 0
(3400 3875);
PAINT SKYBLUE (3400 3875);
DISPLAY INVISIBLE (3400 3875);
FORCEPROP 2 LAST CDS_LIB mstr_symbols
J 0
(3400 3875);
PAINT ORANGE (3400 3875);
DISPLAY INVISIBLE (3400 3875);
FORCEPROP 1 LAST SIZE 1B
J 0
(3475 3825);
DISPLAY 1.723404 (3475 3825);
PAINT GREEN (3475 3825);
DISPLAY INVISIBLE (3475 3825);
FORCEPROP 2 LAST ROOM PVSA_CPU1_PWR_VR
J 0
(2850 3950);
DISPLAY 1.936170 (2850 3950);
PAINT ORANGE (2850 3950);
DISPLAY INVISIBLE (2850 3950);
FORCEPROP 2 LAST BOM_COST PROC_VRD_VCCIN_CPU0
J 0
(3025 3950);
DISPLAY 1.446809 (3025 3950);
PAINT MONO (3025 3950);
DISPLAY INVISIBLE (3025 3950);
FORCEPROP 1 LAST BODY_TYPE PLUMBING
J 0
(3355 3832);
DISPLAY 0.340426 (3355 3832);
PAINT GREEN (3355 3832);
DISPLAY INVISIBLE (3355 3832);
FORCEPROP 1 LAST HDL_POWER GND
J 0
(3400 4025);
DISPLAY 1.723404 (3400 4025);
PAINT GREEN (3400 4025);
DISPLAY INVISIBLE (3400 4025);
FORCEADD SHUNT..1
(-1250 1750);
FORCEPROP 1 LAST LOCATION SH3D2
J 0
(-1325 1800);
DISPLAY 0.617021 (-1325 1800);
PAINT AQUA (-1325 1800);
FORCEPROP 1 LAST PART_NUMBER N_A
J 0
(-1325 1660);
DISPLAY 0.617021 (-1325 1660);
PAINT BLUE (-1325 1660);
FORCEPROP 1 LASTPIN (-1100 1750) $PN 2
J 0
(-1140 1760);
DISPLAY 0.617021 (-1140 1760);
PAINT ORANGE (-1140 1760);
FORCEPROP 1 LASTPIN (-1400 1750) $PN 1
J 2
(-1350 1760);
DISPLAY 0.617021 (-1350 1760);
PAINT ORANGE (-1350 1760);
FORCEPROP 2 LAST SEC_TYPE SH0201
J 0
(-1300 1900);
DISPLAY 1.021277 (-1300 1900);
PAINT ORANGE (-1300 1900);
DISPLAY INVISIBLE (-1300 1900);
FORCEPROP 0 LAST SEC 1
J 0
(-1325 1850);
DISPLAY 0.680851 (-1325 1850);
PAINT MONO (-1325 1850);
DISPLAY INVISIBLE (-1325 1850);
FORCEPROP 1 LAST PATH I129
J 0
(-1300 1850);
DISPLAY 0.978723 (-1300 1850);
PAINT ORANGE (-1300 1850);
DISPLAY INVISIBLE (-1300 1850);
FORCEPROP 2 LAST CDS_LIB mstr_misc
J 0
(-1250 1750);
PAINT ORANGE (-1250 1750);
DISPLAY INVISIBLE (-1250 1750);
FORCEPROP 1 LAST MATERIAL EMPTY
J 0
(-1325 1615);
DISPLAY 0.978723 (-1325 1615);
PAINT RED (-1325 1615);
DISPLAY INVISIBLE (-1325 1615);
FORCEPROP 1 LAST PACK_TYPE SH0201
J 0
(-1310 1565);
DISPLAY 0.978723 (-1310 1565);
PAINT SKYBLUE (-1310 1565);
DISPLAY INVISIBLE (-1310 1565);
FORCEPROP 1 LAST PIN_SHORT A:B
J 0
(-1325 1500);
DISPLAY 1.021277 (-1325 1500);
PAINT ORANGE (-1325 1500);
DISPLAY INVISIBLE (-1325 1500);
FORCEADD SHUNT..1
(-1250 1300);
FORCEPROP 1 LASTPIN (-1400 1300) $PN 1
J 2
(-1350 1310);
DISPLAY 0.617021 (-1350 1310);
PAINT ORANGE (-1350 1310);
FORCEPROP 1 LAST PART_NUMBER N_A
J 0
(-1325 1210);
DISPLAY 0.617021 (-1325 1210);
PAINT BLUE (-1325 1210);
FORCEPROP 1 LASTPIN (-1100 1300) $PN 2
J 0
(-1140 1310);
DISPLAY 0.617021 (-1140 1310);
PAINT ORANGE (-1140 1310);
FORCEPROP 1 LAST LOCATION SH3D1
J 0
(-1325 1350);
DISPLAY 0.617021 (-1325 1350);
PAINT AQUA (-1325 1350);
FORCEPROP 2 LAST CDS_LIB mstr_misc
J 0
(-1250 1300);
PAINT ORANGE (-1250 1300);
DISPLAY INVISIBLE (-1250 1300);
FORCEPROP 2 LAST SEC_TYPE SH0201
J 0
(-1300 1450);
DISPLAY 1.021277 (-1300 1450);
PAINT ORANGE (-1300 1450);
DISPLAY INVISIBLE (-1300 1450);
FORCEPROP 0 LAST SEC 1
J 0
(-1325 1400);
DISPLAY 0.680851 (-1325 1400);
PAINT MONO (-1325 1400);
DISPLAY INVISIBLE (-1325 1400);
FORCEPROP 1 LAST PATH I130
J 0
(-1300 1400);
DISPLAY 0.978723 (-1300 1400);
PAINT ORANGE (-1300 1400);
DISPLAY INVISIBLE (-1300 1400);
FORCEPROP 1 LAST MATERIAL EMPTY
J 0
(-1325 1165);
DISPLAY 0.978723 (-1325 1165);
PAINT RED (-1325 1165);
DISPLAY INVISIBLE (-1325 1165);
FORCEPROP 1 LAST PACK_TYPE SH0201
J 0
(-1310 1115);
DISPLAY 0.978723 (-1310 1115);
PAINT SKYBLUE (-1310 1115);
DISPLAY INVISIBLE (-1310 1115);
FORCEPROP 1 LAST PIN_SHORT A:B
J 0
(-1325 1050);
DISPLAY 1.021277 (-1325 1050);
PAINT ORANGE (-1325 1050);
DISPLAY INVISIBLE (-1325 1050);
FORCEADD GND..1
(2200 2850);
FORCEPROP 3 LASTPIN (2200 2900) SIG_NAME GND\g
J 0
(2210 2910);
DISPLAY 0.659574 (2210 2910);
PAINT MONO (2210 2910);
DISPLAY INVISIBLE (2210 2910);
FORCEPROP 2 LAST CDS_LIB mstr_symbols
J 0
(2200 2850);
PAINT MONO (2200 2850);
DISPLAY INVISIBLE (2200 2850);
FORCEPROP 2 LAST ROOM PVCCIN_CPU0_PWR_VR
J 0
(1650 2925);
DISPLAY 1.936170 (1650 2925);
PAINT ORANGE (1650 2925);
DISPLAY INVISIBLE (1650 2925);
FORCEPROP 2 LAST BOM_COST PROC_VRD_VCCIN_CPU0
J 0
(1825 2925);
DISPLAY 1.446809 (1825 2925);
PAINT MONO (1825 2925);
DISPLAY INVISIBLE (1825 2925);
FORCEPROP 1 LAST VOLTAGE 0
J 0
(2200 2850);
PAINT SKYBLUE (2200 2850);
DISPLAY INVISIBLE (2200 2850);
FORCEPROP 1 LAST SIZE 1B
J 0
(2275 2800);
DISPLAY 1.723404 (2275 2800);
PAINT GREEN (2275 2800);
DISPLAY INVISIBLE (2275 2800);
FORCEPROP 1 LAST PATH I133
J 0
(2275 2850);
DISPLAY 0.872340 (2275 2850);
PAINT AQUA (2275 2850);
DISPLAY INVISIBLE (2275 2850);
FORCEPROP 1 LAST BODY_TYPE PLUMBING
J 0
(2155 2807);
DISPLAY 0.340426 (2155 2807);
PAINT GREEN (2155 2807);
DISPLAY INVISIBLE (2155 2807);
FORCEPROP 1 LAST HDL_POWER GND
J 0
(2200 3000);
DISPLAY 1.723404 (2200 3000);
PAINT GREEN (2200 3000);
DISPLAY INVISIBLE (2200 3000);
FORCEADD CAP..1
(2275 3950);
FORCEPROP 1 LASTPIN (2275 3850) $PN 2
J 0
(2285 3830);
DISPLAY 0.787234 (2285 3830);
PAINT ORANGE (2285 3830);
FORCEPROP 1 LASTPIN (2275 4050) $PN 1
J 0
(2285 4030);
DISPLAY 0.787234 (2285 4030);
PAINT ORANGE (2285 4030);
FORCEPROP 1 LAST VALUE 1000PF
J 0
(2325 4000);
DISPLAY 0.617021 (2325 4000);
PAINT SKYBLUE (2325 4000);
FORCEPROP 1 LAST LOCATION CT61
J 0
(2125 3950);
DISPLAY 0.617021 (2125 3950);
PAINT AQUA (2125 3950);
FORCEPROP 0 LAST POP NOPOP
J 0
(2050 4000);
DISPLAY 1.021277 (2050 4000);
PAINT RED (2050 4000);
FORCEPROP 1 LAST VOLTAGE 50V
J 0
(2325 3950);
DISPLAY 0.617021 (2325 3950);
PAINT SKYBLUE (2325 3950);
FORCEPROP 1 LAST TOLERANCE 10%
J 0
(2325 3900);
DISPLAY 0.617021 (2325 3900);
PAINT SKYBLUE (2325 3900);
FORCEPROP 1 LAST MATERIAL X7R
J 0
(2325 3850);
DISPLAY 0.617021 (2325 3850);
PAINT SKYBLUE (2325 3850);
FORCEPROP 1 LAST PART_NUMBER A36096-046
J 0
(2325 3800);
DISPLAY 0.617021 (2325 3800);
PAINT BLUE (2325 3800);
FORCEPROP 1 LAST PACK_TYPE 0402LF
J 0
(2325 3750);
DISPLAY 0.617021 (2325 3750);
PAINT SKYBLUE (2325 3750);
FORCEPROP 0 LAST ROOM VDDQ_KLM_PWR_VR
J 0
(2325 4150);
DISPLAY 1.021277 (2325 4150);
PAINT ORANGE (2325 4150);
DISPLAY INVISIBLE (2325 4150);
FORCEPROP 1 LAST PATH I134
J 0
(2325 4100);
DISPLAY 0.978723 (2325 4100);
PAINT WHITE (2325 4100);
DISPLAY INVISIBLE (2325 4100);
FORCEPROP 2 LAST CDS_LIB mstr_discrete
J 0
(2275 3950);
PAINT MONO (2275 3950);
DISPLAY INVISIBLE (2275 3950);
FORCEPROP 0 LAST SEC 1
J 0
(2325 4050);
DISPLAY 0.680851 (2325 4050);
PAINT MONO (2325 4050);
DISPLAY INVISIBLE (2325 4050);
FORCEPROP 2 LAST SEC_TYPE 0402LF
J 0
(2325 4150);
DISPLAY 1.021277 (2325 4150);
PAINT ORANGE (2325 4150);
DISPLAY INVISIBLE (2325 4150);
FORCEADD GND..1
(2275 3750);
FORCEPROP 3 LASTPIN (2275 3800) SIG_NAME GND\g
J 0
(2285 3810);
DISPLAY 0.659574 (2285 3810);
PAINT MONO (2285 3810);
DISPLAY INVISIBLE (2285 3810);
FORCEPROP 1 LAST SIZE 1B
J 0
(2350 3700);
DISPLAY 1.170213 (2350 3700);
PAINT AQUA (2350 3700);
DISPLAY INVISIBLE (2350 3700);
FORCEPROP 1 LAST VOLTAGE 0
J 0
(2275 3750);
PAINT SKYBLUE (2275 3750);
DISPLAY INVISIBLE (2275 3750);
FORCEPROP 2 LAST ROOM VDDQ_KLM_PWR_VR
J 0
(1700 3825);
DISPLAY 1.361702 (1700 3825);
PAINT ORANGE (1700 3825);
DISPLAY INVISIBLE (1700 3825);
FORCEPROP 1 LAST PATH I135
J 0
(2350 3750);
DISPLAY 0.872340 (2350 3750);
PAINT AQUA (2350 3750);
DISPLAY INVISIBLE (2350 3750);
FORCEPROP 2 LAST CDS_LIB mstr_symbols
J 0
(2275 3750);
PAINT MONO (2275 3750);
DISPLAY INVISIBLE (2275 3750);
FORCEPROP 1 LAST BODY_TYPE PLUMBING
J 0
(2230 3707);
DISPLAY 0.340426 (2230 3707);
PAINT GREEN (2230 3707);
DISPLAY INVISIBLE (2230 3707);
FORCEPROP 1 LAST HDL_POWER GND
J 0
(2275 3900);
DISPLAY 1.170213 (2275 3900);
PAINT GREEN (2275 3900);
DISPLAY INVISIBLE (2275 3900);
FORCEADD GND..1
(275 3175);
FORCEPROP 3 LASTPIN (275 3225) SIG_NAME GND\g
J 0
(285 3235);
DISPLAY 0.659574 (285 3235);
PAINT MONO (285 3235);
DISPLAY INVISIBLE (285 3235);
FORCEPROP 2 LAST CDS_LIB mstr_symbols
J 0
(275 3175);
PAINT MONO (275 3175);
DISPLAY INVISIBLE (275 3175);
FORCEPROP 1 LAST PATH I136
J 0
(350 3175);
DISPLAY 0.872340 (350 3175);
PAINT AQUA (350 3175);
DISPLAY INVISIBLE (350 3175);
FORCEPROP 2 LAST ROOM PVCCIN_CPU0_PWR_VR
J 0
(-275 3250);
DISPLAY 1.936170 (-275 3250);
PAINT ORANGE (-275 3250);
DISPLAY INVISIBLE (-275 3250);
FORCEPROP 2 LAST BOM_COST PROC_VRD_VCCIN_CPU0
J 0
(-100 3250);
DISPLAY 1.446809 (-100 3250);
PAINT MONO (-100 3250);
DISPLAY INVISIBLE (-100 3250);
FORCEPROP 1 LAST SIZE 1B
J 0
(350 3125);
DISPLAY 1.723404 (350 3125);
PAINT GREEN (350 3125);
DISPLAY INVISIBLE (350 3125);
FORCEPROP 1 LAST VOLTAGE 0
J 0
(275 3175);
PAINT SKYBLUE (275 3175);
DISPLAY INVISIBLE (275 3175);
FORCEPROP 1 LAST BODY_TYPE PLUMBING
J 0
(230 3132);
DISPLAY 0.340426 (230 3132);
PAINT GREEN (230 3132);
DISPLAY INVISIBLE (230 3132);
FORCEPROP 1 LAST HDL_POWER GND
J 0
(275 3325);
DISPLAY 1.723404 (275 3325);
PAINT GREEN (275 3325);
DISPLAY INVISIBLE (275 3325);
FORCEADD CAP_A..1
(275 3425);
FORCEPROP 1 LASTPIN (275 3325) $PN 2
J 0
(285 3305);
DISPLAY 0.787234 (285 3305);
PAINT ORANGE (285 3305);
FORCEPROP 1 LASTPIN (275 3525) $PN 1
J 0
(285 3505);
DISPLAY 0.787234 (285 3505);
PAINT ORANGE (285 3505);
FORCEPROP 1 LAST VALUE 0.1UF
J 0
(325 3475);
DISPLAY 0.617021 (325 3475);
PAINT SKYBLUE (325 3475);
FORCEPROP 0 LAST POP NOPOP
J 0
(25 3475);
DISPLAY 1.021277 (25 3475);
PAINT RED (25 3475);
FORCEPROP 1 LAST LOCATION CT63
J 0
(125 3425);
DISPLAY 0.617021 (125 3425);
PAINT AQUA (125 3425);
FORCEPROP 1 LAST VOLTAGE 16V
J 0
(325 3425);
DISPLAY 0.617021 (325 3425);
PAINT SKYBLUE (325 3425);
FORCEPROP 1 LAST TOLERANCE 10%
J 0
(325 3375);
DISPLAY 0.617021 (325 3375);
PAINT SKYBLUE (325 3375);
FORCEPROP 1 LAST MATERIAL X7R
J 0
(325 3325);
DISPLAY 0.617021 (325 3325);
PAINT SKYBLUE (325 3325);
FORCEPROP 1 LAST PART_NUMBER A36096-030
J 0
(325 3275);
DISPLAY 0.617021 (325 3275);
PAINT BLUE (325 3275);
FORCEPROP 1 LAST PACK_TYPE 0402V
J 0
(325 3225);
DISPLAY 0.617021 (325 3225);
PAINT SKYBLUE (325 3225);
FORCEPROP 2 LAST CDS_LIB dev_discrete
J 0
(275 3425);
PAINT MONO (275 3425);
DISPLAY INVISIBLE (275 3425);
FORCEPROP 1 LAST PATH I137
J 0
(325 3575);
DISPLAY 0.978723 (325 3575);
PAINT WHITE (325 3575);
DISPLAY INVISIBLE (325 3575);
FORCEPROP 2 LAST ROOM PVCCIN_CPU0_PWR_VR
J 0
(325 3575);
DISPLAY 1.361702 (325 3575);
PAINT ORANGE (325 3575);
DISPLAY INVISIBLE (325 3575);
FORCEPROP 0 LAST SEC 1
J 0
(325 3525);
DISPLAY 0.680851 (325 3525);
PAINT MONO (325 3525);
DISPLAY INVISIBLE (325 3525);
FORCEPROP 2 LAST SEC_TYPE 0402V
J 0
(325 3625);
DISPLAY 1.021277 (325 3625);
PAINT ORANGE (325 3625);
DISPLAY INVISIBLE (325 3625);
FORCEADD CAP..1
(2200 3450);
FORCEPROP 0 LAST POP NOPOP
J 0
(2425 3525);
DISPLAY 0.808511 (2425 3525);
PAINT RED (2425 3525);
FORCEPROP 1 LAST PART_NUMBER A36096-046
J 0
(2400 3475);
DISPLAY 0.617021 (2400 3475);
PAINT BLUE (2400 3475);
FORCEPROP 1 LAST PACK_TYPE 0402LF
J 0
(2400 3425);
DISPLAY 0.617021 (2400 3425);
PAINT SKYBLUE (2400 3425);
FORCEPROP 1 LAST LOCATION CT62
J 0
(2250 3550);
DISPLAY 0.617021 (2250 3550);
PAINT AQUA (2250 3550);
FORCEPROP 1 LASTPIN (2200 3550) $PN 1
J 0
(2210 3530);
DISPLAY 0.787234 (2210 3530);
PAINT ORANGE (2210 3530);
FORCEPROP 1 LAST VALUE 1000PF
J 0
(2250 3500);
DISPLAY 0.617021 (2250 3500);
PAINT SKYBLUE (2250 3500);
FORCEPROP 1 LASTPIN (2200 3350) $PN 2
J 0
(2210 3330);
DISPLAY 0.787234 (2210 3330);
PAINT ORANGE (2210 3330);
FORCEPROP 1 LAST VOLTAGE 50V
J 0
(2250 3450);
DISPLAY 0.617021 (2250 3450);
PAINT SKYBLUE (2250 3450);
FORCEPROP 1 LAST TOLERANCE 10%
J 0
(2250 3400);
DISPLAY 0.617021 (2250 3400);
PAINT SKYBLUE (2250 3400);
FORCEPROP 1 LAST MATERIAL X7R
J 0
(2250 3350);
DISPLAY 0.617021 (2250 3350);
PAINT SKYBLUE (2250 3350);
FORCEPROP 2 LAST SEC_TYPE 0402LF
J 0
(2250 3650);
DISPLAY 1.021277 (2250 3650);
PAINT ORANGE (2250 3650);
DISPLAY INVISIBLE (2250 3650);
FORCEPROP 0 LAST SEC 1
J 0
(2250 3600);
DISPLAY 0.680851 (2250 3600);
PAINT MONO (2250 3600);
DISPLAY INVISIBLE (2250 3600);
FORCEPROP 0 LAST ROOM VDDQ_KLM_PWR_VR
J 0
(2250 3650);
DISPLAY 1.021277 (2250 3650);
PAINT ORANGE (2250 3650);
DISPLAY INVISIBLE (2250 3650);
FORCEPROP 1 LAST PATH I143
J 0
(2250 3600);
DISPLAY 0.978723 (2250 3600);
PAINT WHITE (2250 3600);
DISPLAY INVISIBLE (2250 3600);
FORCEPROP 2 LAST CDS_LIB mstr_discrete
J 0
(2200 3450);
PAINT MONO (2200 3450);
DISPLAY INVISIBLE (2200 3450);
FORCEADD RES..1
(-675 3700);
FORCEPROP 1 LASTPIN (-775 3700) $PN 1
J 0
(-763 3712);
DISPLAY 0.787234 (-763 3712);
PAINT ORANGE (-763 3712);
FORCEPROP 1 LASTPIN (-575 3700) $PN 2
J 0
(-613 3712);
DISPLAY 0.787234 (-613 3712);
PAINT ORANGE (-613 3712);
FORCEPROP 1 LAST LOCATION RT41
J 0
(-725 3750);
DISPLAY 0.617021 (-725 3750);
PAINT AQUA (-725 3750);
FORCEPROP 1 LAST VALUE 0
J 2
(-725 3550);
DISPLAY 0.617021 (-725 3550);
PAINT SKYBLUE (-725 3550);
FORCEPROP 1 LAST MATERIAL CHIP
J 0
(-675 3550);
DISPLAY 0.617021 (-675 3550);
PAINT SKYBLUE (-675 3550);
FORCEPROP 1 LAST TOLERANCE 5.0%
J 0
(-675 3600);
DISPLAY 0.617021 (-675 3600);
PAINT SKYBLUE (-675 3600);
FORCEPROP 1 LAST PACK_TYPE 0603
J 0
(-475 3600);
DISPLAY 0.617021 (-475 3600);
PAINT SKYBLUE (-475 3600);
FORCEPROP 1 LAST WATTAGE 1/10W
J 2
(-375 3650);
DISPLAY 0.617021 (-375 3650);
PAINT SKYBLUE (-375 3650);
FORCEPROP 1 LAST PART_NUMBER G22178-002
J 0
(-800 3650);
DISPLAY 0.617021 (-800 3650);
PAINT BLUE (-800 3650);
FORCEPROP 2 LAST CDS_LIB mstr_discrete
J 0
(-675 3700);
PAINT MONO (-675 3700);
DISPLAY INVISIBLE (-675 3700);
FORCEPROP 1 LAST PATH I145
J 0
(-725 3850);
DISPLAY 0.978723 (-725 3850);
PAINT WHITE (-725 3850);
DISPLAY INVISIBLE (-725 3850);
FORCEPROP 0 LAST BOM_COST NT_GBE_BASE
J 0
(-575 3925);
DISPLAY 1.021277 (-575 3925);
PAINT ORANGE (-575 3925);
DISPLAY INVISIBLE (-575 3925);
FORCEPROP 0 LAST ROOM NIC_SPRV
J 0
(-575 3825);
DISPLAY 1.021277 (-575 3825);
PAINT ORANGE (-575 3825);
DISPLAY INVISIBLE (-575 3825);
FORCEPROP 0 LAST SEC 1
J 0
(-925 3800);
DISPLAY 0.680851 (-925 3800);
PAINT MONO (-925 3800);
DISPLAY INVISIBLE (-925 3800);
FORCEPROP 2 LAST SEC_TYPE 0603
J 0
(-725 3900);
DISPLAY 1.021277 (-725 3900);
PAINT ORANGE (-725 3900);
DISPLAY INVISIBLE (-725 3900);
FORCEADD SC22U16V5MX-4-GP..1
(250 1200);
FORCEPROP 2 LASTPIN (250 1275) $PN 1
R 1
J 0
(240 1285);
DISPLAY 0.808511 (240 1285);
PAINT ORANGE (240 1285);
FORCEPROP 2 LASTPIN (250 1125) $PN 2
R 1
J 2
(240 1115);
DISPLAY 0.808511 (240 1115);
PAINT ORANGE (240 1115);
FORCEPROP 1 LAST VALUE SC22U16V5MX-4-GP
R 1
J 0
(325 995);
DISPLAY 0.617021 (325 995);
PAINT GREEN (325 995);
FORCEPROP 1 LAST LOCATION C4E14
J 0
(350 1360);
DISPLAY 0.617021 (350 1360);
PAINT GREEN (350 1360);
FORCEPROP 2 LAST ATTRIBUTE 22UF
J 0
(350 1300);
DISPLAY 0.638298 (350 1300);
PAINT GREEN (350 1300);
FORCEPROP 2 LAST TOLERANCE 20%
J 0
(350 1250);
DISPLAY 0.638298 (350 1250);
PAINT GREEN (350 1250);
FORCEPROP 2 LAST RATED 16V
J 0
(350 1200);
DISPLAY 0.638298 (350 1200);
PAINT GREEN (350 1200);
FORCEPROP 2 LAST TYPE X6S
J 0
(350 1150);
DISPLAY 0.638298 (350 1150);
PAINT GREEN (350 1150);
FORCEPROP 2 LAST PACK_SIZE 0805
J 0
(350 1100);
DISPLAY 0.638298 (350 1100);
PAINT GREEN (350 1100);
FORCEPROP 1 LAST CDS_LMAN_SYM_OUTLINE -50,25,50,-25
J 0
(250 1200);
DISPLAY 0.468085 (250 1200);
PAINT GREEN (250 1200);
DISPLAY INVISIBLE (250 1200);
FORCEPROP 2 LAST CDS_LIB w_hdl
J 0
(250 1200);
PAINT MONO (250 1200);
DISPLAY INVISIBLE (250 1200);
FORCEPROP 1 LAST PART_NUMBER 078.22611.0811
J 0
(250 1200);
DISPLAY 0.617021 (250 1200);
PAINT GREEN (250 1200);
DISPLAY INVISIBLE (250 1200);
FORCEPROP 2 LAST SEC_TYPE SMD-BCG5
J 0
(275 1275);
DISPLAY 1.021277 (275 1275);
PAINT ORANGE (275 1275);
DISPLAY INVISIBLE (275 1275);
FORCEPROP 2 LAST SEC 1
J 0
(275 1275);
DISPLAY 0.680851 (275 1275);
PAINT MONO (275 1275);
DISPLAY INVISIBLE (275 1275);
FORCEPROP 1 LAST PACK_TYPE SMD-BCG5
J 0
(250 1200);
DISPLAY 0.617021 (250 1200);
PAINT GREEN (250 1200);
DISPLAY INVISIBLE (250 1200);
FORCEPROP 1 LAST PATH I148
J 0
(250 1200);
DISPLAY 0.617021 (250 1200);
PAINT GREEN (250 1200);
DISPLAY INVISIBLE (250 1200);
FORCEADD SC22U16V5MX-4-GP..1
(550 1200);
FORCEPROP 2 LASTPIN (550 1275) $PN 1
R 1
J 0
(540 1285);
DISPLAY 0.808511 (540 1285);
PAINT ORANGE (540 1285);
FORCEPROP 2 LASTPIN (550 1125) $PN 2
R 1
J 2
(540 1115);
DISPLAY 0.808511 (540 1115);
PAINT ORANGE (540 1115);
FORCEPROP 1 LAST VALUE SC22U16V5MX-4-GP
R 1
J 0
(625 995);
DISPLAY 0.617021 (625 995);
PAINT GREEN (625 995);
FORCEPROP 1 LAST LOCATION C22W13
J 0
(650 1360);
DISPLAY 0.617021 (650 1360);
PAINT GREEN (650 1360);
FORCEPROP 2 LAST ATTRIBUTE 22UF
J 0
(650 1300);
DISPLAY 0.638298 (650 1300);
PAINT GREEN (650 1300);
FORCEPROP 2 LAST TOLERANCE 20%
J 0
(650 1250);
DISPLAY 0.638298 (650 1250);
PAINT GREEN (650 1250);
FORCEPROP 2 LAST RATED 16V
J 0
(650 1200);
DISPLAY 0.638298 (650 1200);
PAINT GREEN (650 1200);
FORCEPROP 2 LAST TYPE X6S
J 0
(650 1150);
DISPLAY 0.638298 (650 1150);
PAINT GREEN (650 1150);
FORCEPROP 2 LAST PACK_SIZE 0805
J 0
(650 1100);
DISPLAY 0.638298 (650 1100);
PAINT GREEN (650 1100);
FORCEPROP 1 LAST PACK_TYPE SMD-BCG5
J 0
(550 1200);
DISPLAY 0.617021 (550 1200);
PAINT GREEN (550 1200);
DISPLAY INVISIBLE (550 1200);
FORCEPROP 2 LAST SEC 1
J 0
(575 1275);
DISPLAY 0.680851 (575 1275);
PAINT MONO (575 1275);
DISPLAY INVISIBLE (575 1275);
FORCEPROP 2 LAST SEC_TYPE SMD-BCG5
J 0
(575 1275);
DISPLAY 1.021277 (575 1275);
PAINT ORANGE (575 1275);
DISPLAY INVISIBLE (575 1275);
FORCEPROP 1 LAST PART_NUMBER 078.22611.0811
J 0
(550 1200);
DISPLAY 0.617021 (550 1200);
PAINT GREEN (550 1200);
DISPLAY INVISIBLE (550 1200);
FORCEPROP 2 LAST CDS_LIB w_hdl
J 0
(550 1200);
PAINT MONO (550 1200);
DISPLAY INVISIBLE (550 1200);
FORCEPROP 1 LAST CDS_LMAN_SYM_OUTLINE -50,25,50,-25
J 0
(550 1200);
DISPLAY 0.468085 (550 1200);
PAINT GREEN (550 1200);
DISPLAY INVISIBLE (550 1200);
FORCEPROP 1 LAST PATH I149
J 0
(550 1200);
DISPLAY 0.617021 (550 1200);
PAINT GREEN (550 1200);
DISPLAY INVISIBLE (550 1200);
FORCEADD GND..1
(550 950);
FORCEPROP 3 LASTPIN (550 1000) SIG_NAME GND\g
J 0
(560 1010);
DISPLAY 0.659574 (560 1010);
PAINT MONO (560 1010);
DISPLAY INVISIBLE (560 1010);
FORCEPROP 1 LAST SIZE 1B
J 0
(625 900);
DISPLAY 0.872340 (625 900);
PAINT GREEN (625 900);
DISPLAY INVISIBLE (625 900);
FORCEPROP 1 LAST VOLTAGE 0
J 0
(550 950);
PAINT SKYBLUE (550 950);
DISPLAY INVISIBLE (550 950);
FORCEPROP 2 LAST ROOM PVPP_KLM_VR
J 0
(-25 1025);
DISPLAY 1.042553 (-25 1025);
PAINT GREEN (-25 1025);
DISPLAY INVISIBLE (-25 1025);
FORCEPROP 2 LAST BOM_COST PVPP_KLM_VR
J 0
(-300 1025);
DISPLAY 1.042553 (-300 1025);
PAINT WHITE (-300 1025);
DISPLAY INVISIBLE (-300 1025);
FORCEPROP 2 LAST CDS_LIB mstr_symbols
J 0
(550 950);
PAINT MONO (550 950);
DISPLAY INVISIBLE (550 950);
FORCEPROP 1 LAST PATH I150
J 0
(625 950);
DISPLAY 0.872340 (625 950);
PAINT AQUA (625 950);
DISPLAY INVISIBLE (625 950);
FORCEPROP 1 LAST BODY_TYPE PLUMBING
J 0
(505 907);
DISPLAY 0.340426 (505 907);
PAINT GREEN (505 907);
DISPLAY INVISIBLE (505 907);
FORCEPROP 1 LAST HDL_POWER GND
J 0
(550 1100);
DISPLAY 0.872340 (550 1100);
PAINT GREEN (550 1100);
DISPLAY INVISIBLE (550 1100);
FORCEADD GND..1
(250 950);
FORCEPROP 3 LASTPIN (250 1000) SIG_NAME GND\g
J 0
(260 1010);
DISPLAY 0.659574 (260 1010);
PAINT MONO (260 1010);
DISPLAY INVISIBLE (260 1010);
FORCEPROP 1 LAST SIZE 1B
J 0
(325 900);
DISPLAY 0.872340 (325 900);
PAINT GREEN (325 900);
DISPLAY INVISIBLE (325 900);
FORCEPROP 1 LAST VOLTAGE 0
J 0
(250 950);
PAINT SKYBLUE (250 950);
DISPLAY INVISIBLE (250 950);
FORCEPROP 2 LAST ROOM PVPP_KLM_VR
J 0
(-325 1025);
DISPLAY 1.042553 (-325 1025);
PAINT GREEN (-325 1025);
DISPLAY INVISIBLE (-325 1025);
FORCEPROP 2 LAST BOM_COST PVPP_KLM_VR
J 0
(-600 1025);
DISPLAY 1.042553 (-600 1025);
PAINT WHITE (-600 1025);
DISPLAY INVISIBLE (-600 1025);
FORCEPROP 2 LAST CDS_LIB mstr_symbols
J 0
(250 950);
PAINT MONO (250 950);
DISPLAY INVISIBLE (250 950);
FORCEPROP 1 LAST PATH I151
J 0
(325 950);
DISPLAY 0.872340 (325 950);
PAINT AQUA (325 950);
DISPLAY INVISIBLE (325 950);
FORCEPROP 1 LAST BODY_TYPE PLUMBING
J 0
(205 907);
DISPLAY 0.340426 (205 907);
PAINT GREEN (205 907);
DISPLAY INVISIBLE (205 907);
FORCEPROP 1 LAST HDL_POWER GND
J 0
(250 1100);
DISPLAY 0.872340 (250 1100);
PAINT GREEN (250 1100);
DISPLAY INVISIBLE (250 1100);
FORCEADD SC22U16V5MX-4-GP..1
(850 1200);
FORCEPROP 2 LASTPIN (850 1125) $PN 2
R 1
J 2
(840 1115);
DISPLAY 0.808511 (840 1115);
PAINT ORANGE (840 1115);
FORCEPROP 2 LASTPIN (850 1275) $PN 1
R 1
J 0
(840 1285);
DISPLAY 0.808511 (840 1285);
PAINT ORANGE (840 1285);
FORCEPROP 1 LAST VALUE SC22U16V5MX-4-GP
R 1
J 0
(925 995);
DISPLAY 0.617021 (925 995);
PAINT GREEN (925 995);
FORCEPROP 1 LAST LOCATION C22W14
J 0
(950 1360);
DISPLAY 0.617021 (950 1360);
PAINT GREEN (950 1360);
FORCEPROP 2 LAST ATTRIBUTE 22UF
J 0
(950 1300);
DISPLAY 0.638298 (950 1300);
PAINT GREEN (950 1300);
FORCEPROP 2 LAST TOLERANCE 20%
J 0
(950 1250);
DISPLAY 0.638298 (950 1250);
PAINT GREEN (950 1250);
FORCEPROP 2 LAST RATED 16V
J 0
(950 1200);
DISPLAY 0.638298 (950 1200);
PAINT GREEN (950 1200);
FORCEPROP 2 LAST TYPE X6S
J 0
(950 1150);
DISPLAY 0.638298 (950 1150);
PAINT GREEN (950 1150);
FORCEPROP 2 LAST PACK_SIZE 0805
J 0
(950 1100);
DISPLAY 0.638298 (950 1100);
PAINT GREEN (950 1100);
FORCEPROP 1 LAST PACK_TYPE SMD-BCG5
J 0
(850 1200);
DISPLAY 0.617021 (850 1200);
PAINT GREEN (850 1200);
DISPLAY INVISIBLE (850 1200);
FORCEPROP 2 LAST SEC 1
J 0
(875 1275);
DISPLAY 0.680851 (875 1275);
PAINT MONO (875 1275);
DISPLAY INVISIBLE (875 1275);
FORCEPROP 2 LAST SEC_TYPE SMD-BCG5
J 0
(875 1275);
DISPLAY 1.021277 (875 1275);
PAINT ORANGE (875 1275);
DISPLAY INVISIBLE (875 1275);
FORCEPROP 1 LAST PART_NUMBER 078.22611.0811
J 0
(850 1200);
DISPLAY 0.617021 (850 1200);
PAINT GREEN (850 1200);
DISPLAY INVISIBLE (850 1200);
FORCEPROP 2 LAST CDS_LIB w_hdl
J 0
(850 1200);
PAINT MONO (850 1200);
DISPLAY INVISIBLE (850 1200);
FORCEPROP 1 LAST CDS_LMAN_SYM_OUTLINE -50,25,50,-25
J 0
(850 1200);
DISPLAY 0.468085 (850 1200);
PAINT GREEN (850 1200);
DISPLAY INVISIBLE (850 1200);
FORCEPROP 1 LAST PATH I152
J 0
(850 1200);
DISPLAY 0.617021 (850 1200);
PAINT GREEN (850 1200);
DISPLAY INVISIBLE (850 1200);
FORCEADD GND..1
(850 950);
FORCEPROP 3 LASTPIN (850 1000) SIG_NAME GND\g
J 0
(860 1010);
DISPLAY 0.659574 (860 1010);
PAINT MONO (860 1010);
DISPLAY INVISIBLE (860 1010);
FORCEPROP 1 LAST SIZE 1B
J 0
(925 900);
DISPLAY 0.872340 (925 900);
PAINT GREEN (925 900);
DISPLAY INVISIBLE (925 900);
FORCEPROP 1 LAST VOLTAGE 0
J 0
(850 950);
PAINT SKYBLUE (850 950);
DISPLAY INVISIBLE (850 950);
FORCEPROP 2 LAST ROOM PVPP_KLM_VR
J 0
(275 1025);
DISPLAY 1.042553 (275 1025);
PAINT GREEN (275 1025);
DISPLAY INVISIBLE (275 1025);
FORCEPROP 2 LAST BOM_COST PVPP_KLM_VR
J 0
(0 1025);
DISPLAY 1.042553 (0 1025);
PAINT WHITE (0 1025);
DISPLAY INVISIBLE (0 1025);
FORCEPROP 2 LAST CDS_LIB mstr_symbols
J 0
(850 950);
PAINT MONO (850 950);
DISPLAY INVISIBLE (850 950);
FORCEPROP 1 LAST PATH I153
J 0
(925 950);
DISPLAY 0.872340 (925 950);
PAINT AQUA (925 950);
DISPLAY INVISIBLE (925 950);
FORCEPROP 1 LAST BODY_TYPE PLUMBING
J 0
(805 907);
DISPLAY 0.340426 (805 907);
PAINT GREEN (805 907);
DISPLAY INVISIBLE (805 907);
FORCEPROP 1 LAST HDL_POWER GND
J 0
(850 1100);
DISPLAY 0.872340 (850 1100);
PAINT GREEN (850 1100);
DISPLAY INVISIBLE (850 1100);
FORCEADD SC22U16V5MX-4-GP..1
(1150 1200);
FORCEPROP 2 LASTPIN (1150 1275) $PN 1
R 1
J 0
(1140 1285);
DISPLAY 0.808511 (1140 1285);
PAINT ORANGE (1140 1285);
FORCEPROP 2 LASTPIN (1150 1125) $PN 2
R 1
J 2
(1140 1115);
DISPLAY 0.808511 (1140 1115);
PAINT ORANGE (1140 1115);
FORCEPROP 1 LAST LOCATION C22W15
J 0
(1250 1360);
DISPLAY 0.617021 (1250 1360);
PAINT GREEN (1250 1360);
FORCEPROP 1 LAST VALUE SC22U16V5MX-4-GP
R 1
J 0
(1225 970);
DISPLAY 0.617021 (1225 970);
PAINT GREEN (1225 970);
FORCEPROP 2 LAST ATTRIBUTE 22UF
J 0
(1250 1300);
DISPLAY 0.638298 (1250 1300);
PAINT GREEN (1250 1300);
FORCEPROP 2 LAST TOLERANCE 20%
J 0
(1250 1250);
DISPLAY 0.638298 (1250 1250);
PAINT GREEN (1250 1250);
FORCEPROP 2 LAST RATED 16V
J 0
(1250 1200);
DISPLAY 0.638298 (1250 1200);
PAINT GREEN (1250 1200);
FORCEPROP 2 LAST PACK_SIZE 0805
J 0
(1250 1100);
DISPLAY 0.638298 (1250 1100);
PAINT GREEN (1250 1100);
FORCEPROP 2 LAST TYPE X6S
J 0
(1250 1150);
DISPLAY 0.638298 (1250 1150);
PAINT GREEN (1250 1150);
FORCEPROP 1 LAST PATH I154
J 0
(1150 1200);
DISPLAY 0.617021 (1150 1200);
PAINT GREEN (1150 1200);
DISPLAY INVISIBLE (1150 1200);
FORCEPROP 1 LAST CDS_LMAN_SYM_OUTLINE -50,25,50,-25
J 0
(1150 1200);
DISPLAY 0.468085 (1150 1200);
PAINT GREEN (1150 1200);
DISPLAY INVISIBLE (1150 1200);
FORCEPROP 2 LAST CDS_LIB w_hdl
J 0
(1150 1200);
PAINT MONO (1150 1200);
DISPLAY INVISIBLE (1150 1200);
FORCEPROP 1 LAST PART_NUMBER 078.22611.0811
J 0
(1150 1200);
DISPLAY 0.617021 (1150 1200);
PAINT GREEN (1150 1200);
DISPLAY INVISIBLE (1150 1200);
FORCEPROP 2 LAST SEC_TYPE SMD-BCG5
J 0
(1175 1275);
DISPLAY 1.021277 (1175 1275);
PAINT ORANGE (1175 1275);
DISPLAY INVISIBLE (1175 1275);
FORCEPROP 2 LAST SEC 1
J 0
(1175 1275);
DISPLAY 0.680851 (1175 1275);
PAINT MONO (1175 1275);
DISPLAY INVISIBLE (1175 1275);
FORCEPROP 1 LAST PACK_TYPE SMD-BCG5
J 0
(1150 1200);
DISPLAY 0.617021 (1150 1200);
PAINT GREEN (1150 1200);
DISPLAY INVISIBLE (1150 1200);
FORCEADD GND..1
(1150 950);
FORCEPROP 3 LASTPIN (1150 1000) SIG_NAME GND\g
J 0
(1160 1010);
DISPLAY 0.659574 (1160 1010);
PAINT MONO (1160 1010);
DISPLAY INVISIBLE (1160 1010);
FORCEPROP 1 LAST PATH I155
J 0
(1225 950);
DISPLAY 0.872340 (1225 950);
PAINT AQUA (1225 950);
DISPLAY INVISIBLE (1225 950);
FORCEPROP 1 LAST SIZE 1B
J 0
(1225 900);
DISPLAY 0.872340 (1225 900);
PAINT GREEN (1225 900);
DISPLAY INVISIBLE (1225 900);
FORCEPROP 1 LAST VOLTAGE 0
J 0
(1150 950);
PAINT SKYBLUE (1150 950);
DISPLAY INVISIBLE (1150 950);
FORCEPROP 2 LAST ROOM PVPP_KLM_VR
J 0
(575 1025);
DISPLAY 1.042553 (575 1025);
PAINT GREEN (575 1025);
DISPLAY INVISIBLE (575 1025);
FORCEPROP 2 LAST BOM_COST PVPP_KLM_VR
J 0
(300 1025);
DISPLAY 1.042553 (300 1025);
PAINT WHITE (300 1025);
DISPLAY INVISIBLE (300 1025);
FORCEPROP 2 LAST CDS_LIB mstr_symbols
J 0
(1150 950);
PAINT MONO (1150 950);
DISPLAY INVISIBLE (1150 950);
FORCEPROP 1 LAST BODY_TYPE PLUMBING
J 0
(1105 907);
DISPLAY 0.340426 (1105 907);
PAINT GREEN (1105 907);
DISPLAY INVISIBLE (1105 907);
FORCEPROP 1 LAST HDL_POWER GND
J 0
(1150 1100);
DISPLAY 0.872340 (1150 1100);
PAINT GREEN (1150 1100);
DISPLAY INVISIBLE (1150 1100);
FORCEADD SC22U16V5MX-4-GP..1
(2500 1200);
FORCEPROP 1 LAST VALUE SC22U16V5MX-4-GP
R 1
J 0
(2575 995);
DISPLAY 0.617021 (2575 995);
PAINT GREEN (2575 995);
FORCEPROP 2 LASTPIN (2500 1275) $PN 1
R 1
J 0
(2490 1285);
DISPLAY 0.808511 (2490 1285);
PAINT ORANGE (2490 1285);
FORCEPROP 2 LAST ATTRIBUTE 22UF
J 0
(2600 1300);
DISPLAY 0.638298 (2600 1300);
PAINT GREEN (2600 1300);
FORCEPROP 2 LASTPIN (2500 1125) $PN 2
R 1
J 2
(2490 1115);
DISPLAY 0.808511 (2490 1115);
PAINT ORANGE (2490 1115);
FORCEPROP 2 LAST PACK_SIZE 0805
J 0
(2600 1100);
DISPLAY 0.638298 (2600 1100);
PAINT GREEN (2600 1100);
FORCEPROP 2 LAST TYPE X6S
J 0
(2600 1150);
DISPLAY 0.638298 (2600 1150);
PAINT GREEN (2600 1150);
FORCEPROP 2 LAST RATED 16V
J 0
(2600 1200);
DISPLAY 0.638298 (2600 1200);
PAINT GREEN (2600 1200);
FORCEPROP 2 LAST TOLERANCE 20%
J 0
(2600 1250);
DISPLAY 0.638298 (2600 1250);
PAINT GREEN (2600 1250);
FORCEPROP 1 LAST LOCATION C22W18
J 0
(2600 1360);
DISPLAY 0.617021 (2600 1360);
PAINT GREEN (2600 1360);
FORCEPROP 1 LAST PACK_TYPE SMD-BCG5
J 0
(2500 1200);
DISPLAY 0.617021 (2500 1200);
PAINT GREEN (2500 1200);
DISPLAY INVISIBLE (2500 1200);
FORCEPROP 2 LAST SEC 1
J 0
(2525 1275);
DISPLAY 0.680851 (2525 1275);
PAINT MONO (2525 1275);
DISPLAY INVISIBLE (2525 1275);
FORCEPROP 2 LAST SEC_TYPE SMD-BCG5
J 0
(2525 1275);
DISPLAY 1.021277 (2525 1275);
PAINT ORANGE (2525 1275);
DISPLAY INVISIBLE (2525 1275);
FORCEPROP 1 LAST PART_NUMBER 078.22611.0811
J 0
(2500 1200);
DISPLAY 0.617021 (2500 1200);
PAINT GREEN (2500 1200);
DISPLAY INVISIBLE (2500 1200);
FORCEPROP 2 LAST CDS_LIB w_hdl
J 0
(2500 1200);
PAINT MONO (2500 1200);
DISPLAY INVISIBLE (2500 1200);
FORCEPROP 1 LAST CDS_LMAN_SYM_OUTLINE -50,25,50,-25
J 0
(2500 1200);
DISPLAY 0.468085 (2500 1200);
PAINT GREEN (2500 1200);
DISPLAY INVISIBLE (2500 1200);
FORCEPROP 1 LAST PATH I156
J 0
(2500 1200);
DISPLAY 0.617021 (2500 1200);
PAINT GREEN (2500 1200);
DISPLAY INVISIBLE (2500 1200);
FORCEADD GND..1
(2500 950);
FORCEPROP 3 LASTPIN (2500 1000) SIG_NAME GND\g
J 0
(2510 1010);
DISPLAY 0.659574 (2510 1010);
PAINT MONO (2510 1010);
DISPLAY INVISIBLE (2510 1010);
FORCEPROP 2 LAST CDS_LIB mstr_symbols
J 0
(2500 950);
PAINT MONO (2500 950);
DISPLAY INVISIBLE (2500 950);
FORCEPROP 2 LAST BOM_COST PVPP_KLM_VR
J 0
(1650 1025);
DISPLAY 1.042553 (1650 1025);
PAINT WHITE (1650 1025);
DISPLAY INVISIBLE (1650 1025);
FORCEPROP 2 LAST ROOM PVPP_KLM_VR
J 0
(1925 1025);
DISPLAY 1.042553 (1925 1025);
PAINT GREEN (1925 1025);
DISPLAY INVISIBLE (1925 1025);
FORCEPROP 1 LAST VOLTAGE 0
J 0
(2500 950);
PAINT SKYBLUE (2500 950);
DISPLAY INVISIBLE (2500 950);
FORCEPROP 1 LAST SIZE 1B
J 0
(2575 900);
DISPLAY 0.872340 (2575 900);
PAINT GREEN (2575 900);
DISPLAY INVISIBLE (2575 900);
FORCEPROP 1 LAST PATH I157
J 0
(2575 950);
DISPLAY 0.872340 (2575 950);
PAINT AQUA (2575 950);
DISPLAY INVISIBLE (2575 950);
FORCEPROP 1 LAST BODY_TYPE PLUMBING
J 0
(2455 907);
DISPLAY 0.340426 (2455 907);
PAINT GREEN (2455 907);
DISPLAY INVISIBLE (2455 907);
FORCEPROP 1 LAST HDL_POWER GND
J 0
(2500 1100);
DISPLAY 0.872340 (2500 1100);
PAINT GREEN (2500 1100);
DISPLAY INVISIBLE (2500 1100);
FORCEADD SC22U16V5MX-4-GP..1
(2200 1200);
FORCEPROP 2 LASTPIN (2200 1125) $PN 2
R 1
J 2
(2190 1115);
DISPLAY 0.808511 (2190 1115);
PAINT ORANGE (2190 1115);
FORCEPROP 1 LAST VALUE SC22U16V5MX-4-GP
R 1
J 0
(2275 995);
DISPLAY 0.617021 (2275 995);
PAINT GREEN (2275 995);
FORCEPROP 2 LAST ATTRIBUTE 22UF
J 0
(2300 1300);
DISPLAY 0.638298 (2300 1300);
PAINT GREEN (2300 1300);
FORCEPROP 2 LAST TOLERANCE 20%
J 0
(2300 1250);
DISPLAY 0.638298 (2300 1250);
PAINT GREEN (2300 1250);
FORCEPROP 2 LASTPIN (2200 1275) $PN 1
R 1
J 0
(2190 1285);
DISPLAY 0.808511 (2190 1285);
PAINT ORANGE (2190 1285);
FORCEPROP 2 LAST RATED 16V
J 0
(2300 1200);
DISPLAY 0.638298 (2300 1200);
PAINT GREEN (2300 1200);
FORCEPROP 2 LAST PACK_SIZE 0805
J 0
(2300 1100);
DISPLAY 0.638298 (2300 1100);
PAINT GREEN (2300 1100);
FORCEPROP 2 LAST TYPE X6S
J 0
(2300 1150);
DISPLAY 0.638298 (2300 1150);
PAINT GREEN (2300 1150);
FORCEPROP 1 LAST LOCATION C22W17
J 0
(2300 1360);
DISPLAY 0.617021 (2300 1360);
PAINT GREEN (2300 1360);
FORCEPROP 1 LAST PATH I158
J 0
(2200 1200);
DISPLAY 0.617021 (2200 1200);
PAINT GREEN (2200 1200);
DISPLAY INVISIBLE (2200 1200);
FORCEPROP 1 LAST CDS_LMAN_SYM_OUTLINE -50,25,50,-25
J 0
(2200 1200);
DISPLAY 0.468085 (2200 1200);
PAINT GREEN (2200 1200);
DISPLAY INVISIBLE (2200 1200);
FORCEPROP 2 LAST CDS_LIB w_hdl
J 0
(2200 1200);
PAINT MONO (2200 1200);
DISPLAY INVISIBLE (2200 1200);
FORCEPROP 1 LAST PART_NUMBER 078.22611.0811
J 0
(2200 1200);
DISPLAY 0.617021 (2200 1200);
PAINT GREEN (2200 1200);
DISPLAY INVISIBLE (2200 1200);
FORCEPROP 2 LAST SEC_TYPE SMD-BCG5
J 0
(2225 1275);
DISPLAY 1.021277 (2225 1275);
PAINT ORANGE (2225 1275);
DISPLAY INVISIBLE (2225 1275);
FORCEPROP 2 LAST SEC 1
J 0
(2225 1275);
DISPLAY 0.680851 (2225 1275);
PAINT MONO (2225 1275);
DISPLAY INVISIBLE (2225 1275);
FORCEPROP 1 LAST PACK_TYPE SMD-BCG5
J 0
(2200 1200);
DISPLAY 0.617021 (2200 1200);
PAINT GREEN (2200 1200);
DISPLAY INVISIBLE (2200 1200);
FORCEADD GND..1
(2200 950);
FORCEPROP 3 LASTPIN (2200 1000) SIG_NAME GND\g
J 0
(2210 1010);
DISPLAY 0.659574 (2210 1010);
PAINT MONO (2210 1010);
DISPLAY INVISIBLE (2210 1010);
FORCEPROP 1 LAST PATH I159
J 0
(2275 950);
DISPLAY 0.872340 (2275 950);
PAINT AQUA (2275 950);
DISPLAY INVISIBLE (2275 950);
FORCEPROP 2 LAST CDS_LIB mstr_symbols
J 0
(2200 950);
PAINT MONO (2200 950);
DISPLAY INVISIBLE (2200 950);
FORCEPROP 2 LAST BOM_COST PVPP_KLM_VR
J 0
(1350 1025);
DISPLAY 1.042553 (1350 1025);
PAINT WHITE (1350 1025);
DISPLAY INVISIBLE (1350 1025);
FORCEPROP 2 LAST ROOM PVPP_KLM_VR
J 0
(1625 1025);
DISPLAY 1.042553 (1625 1025);
PAINT GREEN (1625 1025);
DISPLAY INVISIBLE (1625 1025);
FORCEPROP 1 LAST VOLTAGE 0
J 0
(2200 950);
PAINT SKYBLUE (2200 950);
DISPLAY INVISIBLE (2200 950);
FORCEPROP 1 LAST SIZE 1B
J 0
(2275 900);
DISPLAY 0.872340 (2275 900);
PAINT GREEN (2275 900);
DISPLAY INVISIBLE (2275 900);
FORCEPROP 1 LAST BODY_TYPE PLUMBING
J 0
(2155 907);
DISPLAY 0.340426 (2155 907);
PAINT GREEN (2155 907);
DISPLAY INVISIBLE (2155 907);
FORCEPROP 1 LAST HDL_POWER GND
J 0
(2200 1100);
DISPLAY 0.872340 (2200 1100);
PAINT GREEN (2200 1100);
DISPLAY INVISIBLE (2200 1100);
FORCEADD SC22U16V5MX-4-GP..1
(1900 1200);
FORCEPROP 2 LASTPIN (1900 1125) $PN 2
R 1
J 2
(1890 1115);
DISPLAY 0.808511 (1890 1115);
PAINT ORANGE (1890 1115);
FORCEPROP 1 LAST VALUE SC22U16V5MX-4-GP
R 1
J 0
(1975 995);
DISPLAY 0.617021 (1975 995);
PAINT GREEN (1975 995);
FORCEPROP 2 LAST PACK_SIZE 0805
J 0
(2000 1100);
DISPLAY 0.638298 (2000 1100);
PAINT GREEN (2000 1100);
FORCEPROP 2 LAST TYPE X6S
J 0
(2000 1150);
DISPLAY 0.638298 (2000 1150);
PAINT GREEN (2000 1150);
FORCEPROP 2 LAST RATED 16V
J 0
(2000 1200);
DISPLAY 0.638298 (2000 1200);
PAINT GREEN (2000 1200);
FORCEPROP 2 LAST TOLERANCE 20%
J 0
(2000 1250);
DISPLAY 0.638298 (2000 1250);
PAINT GREEN (2000 1250);
FORCEPROP 2 LASTPIN (1900 1275) $PN 1
R 1
J 0
(1890 1285);
DISPLAY 0.808511 (1890 1285);
PAINT ORANGE (1890 1285);
FORCEPROP 1 LAST LOCATION C22W16
J 0
(2000 1360);
DISPLAY 0.617021 (2000 1360);
PAINT GREEN (2000 1360);
FORCEPROP 2 LAST ATTRIBUTE 22UF
J 0
(2000 1300);
DISPLAY 0.638298 (2000 1300);
PAINT GREEN (2000 1300);
FORCEPROP 1 LAST PATH I160
J 0
(1900 1200);
DISPLAY 0.617021 (1900 1200);
PAINT GREEN (1900 1200);
DISPLAY INVISIBLE (1900 1200);
FORCEPROP 1 LAST CDS_LMAN_SYM_OUTLINE -50,25,50,-25
J 0
(1900 1200);
DISPLAY 0.468085 (1900 1200);
PAINT GREEN (1900 1200);
DISPLAY INVISIBLE (1900 1200);
FORCEPROP 2 LAST CDS_LIB w_hdl
J 0
(1900 1200);
PAINT MONO (1900 1200);
DISPLAY INVISIBLE (1900 1200);
FORCEPROP 1 LAST PART_NUMBER 078.22611.0811
J 0
(1900 1200);
DISPLAY 0.617021 (1900 1200);
PAINT GREEN (1900 1200);
DISPLAY INVISIBLE (1900 1200);
FORCEPROP 2 LAST SEC_TYPE SMD-BCG5
J 0
(1925 1275);
DISPLAY 1.021277 (1925 1275);
PAINT ORANGE (1925 1275);
DISPLAY INVISIBLE (1925 1275);
FORCEPROP 2 LAST SEC 1
J 0
(1925 1275);
DISPLAY 0.680851 (1925 1275);
PAINT MONO (1925 1275);
DISPLAY INVISIBLE (1925 1275);
FORCEPROP 1 LAST PACK_TYPE SMD-BCG5
J 0
(1900 1200);
DISPLAY 0.617021 (1900 1200);
PAINT GREEN (1900 1200);
DISPLAY INVISIBLE (1900 1200);
FORCEADD SC22U16V5MX-4-GP..1
(1600 1200);
FORCEPROP 2 LAST TYPE X6S
J 0
(1700 1150);
DISPLAY 0.638298 (1700 1150);
PAINT GREEN (1700 1150);
FORCEPROP 2 LAST ATTRIBUTE 22UF
J 0
(1700 1300);
DISPLAY 0.638298 (1700 1300);
PAINT GREEN (1700 1300);
FORCEPROP 2 LAST RATED 16V
J 0
(1700 1200);
DISPLAY 0.638298 (1700 1200);
PAINT GREEN (1700 1200);
FORCEPROP 2 LAST PACK_SIZE 0805
J 0
(1700 1100);
DISPLAY 0.638298 (1700 1100);
PAINT GREEN (1700 1100);
FORCEPROP 2 LASTPIN (1600 1125) $PN 2
R 1
J 2
(1590 1115);
DISPLAY 0.808511 (1590 1115);
PAINT ORANGE (1590 1115);
FORCEPROP 1 LAST LOCATION C4E8
J 0
(1700 1360);
DISPLAY 0.617021 (1700 1360);
PAINT GREEN (1700 1360);
FORCEPROP 2 LASTPIN (1600 1275) $PN 1
R 1
J 0
(1590 1285);
DISPLAY 0.808511 (1590 1285);
PAINT ORANGE (1590 1285);
FORCEPROP 2 LAST TOLERANCE 20%
J 0
(1700 1250);
DISPLAY 0.638298 (1700 1250);
PAINT GREEN (1700 1250);
FORCEPROP 1 LAST VALUE SC22U16V5MX-4-GP
R 1
J 0
(1675 995);
DISPLAY 0.617021 (1675 995);
PAINT GREEN (1675 995);
FORCEPROP 1 LAST CDS_LMAN_SYM_OUTLINE -50,25,50,-25
J 0
(1600 1200);
DISPLAY 0.468085 (1600 1200);
PAINT GREEN (1600 1200);
DISPLAY INVISIBLE (1600 1200);
FORCEPROP 2 LAST CDS_LIB w_hdl
J 0
(1600 1200);
PAINT MONO (1600 1200);
DISPLAY INVISIBLE (1600 1200);
FORCEPROP 1 LAST PART_NUMBER 078.22611.0811
J 0
(1600 1200);
DISPLAY 0.617021 (1600 1200);
PAINT GREEN (1600 1200);
DISPLAY INVISIBLE (1600 1200);
FORCEPROP 2 LAST SEC_TYPE SMD-BCG5
J 0
(1625 1275);
DISPLAY 1.021277 (1625 1275);
PAINT ORANGE (1625 1275);
DISPLAY INVISIBLE (1625 1275);
FORCEPROP 2 LAST SEC 1
J 0
(1625 1275);
DISPLAY 0.680851 (1625 1275);
PAINT MONO (1625 1275);
DISPLAY INVISIBLE (1625 1275);
FORCEPROP 1 LAST PACK_TYPE SMD-BCG5
J 0
(1600 1200);
DISPLAY 0.617021 (1600 1200);
PAINT GREEN (1600 1200);
DISPLAY INVISIBLE (1600 1200);
FORCEPROP 1 LAST PATH I161
J 0
(1600 1200);
DISPLAY 0.617021 (1600 1200);
PAINT GREEN (1600 1200);
DISPLAY INVISIBLE (1600 1200);
FORCEADD GND..1
(1900 950);
FORCEPROP 3 LASTPIN (1900 1000) SIG_NAME GND\g
J 0
(1910 1010);
DISPLAY 0.659574 (1910 1010);
PAINT MONO (1910 1010);
DISPLAY INVISIBLE (1910 1010);
FORCEPROP 1 LAST PATH I162
J 0
(1975 950);
DISPLAY 0.872340 (1975 950);
PAINT AQUA (1975 950);
DISPLAY INVISIBLE (1975 950);
FORCEPROP 2 LAST CDS_LIB mstr_symbols
J 0
(1900 950);
PAINT MONO (1900 950);
DISPLAY INVISIBLE (1900 950);
FORCEPROP 2 LAST BOM_COST PVPP_KLM_VR
J 0
(1050 1025);
DISPLAY 1.042553 (1050 1025);
PAINT WHITE (1050 1025);
DISPLAY INVISIBLE (1050 1025);
FORCEPROP 2 LAST ROOM PVPP_KLM_VR
J 0
(1325 1025);
DISPLAY 1.042553 (1325 1025);
PAINT GREEN (1325 1025);
DISPLAY INVISIBLE (1325 1025);
FORCEPROP 1 LAST VOLTAGE 0
J 0
(1900 950);
PAINT SKYBLUE (1900 950);
DISPLAY INVISIBLE (1900 950);
FORCEPROP 1 LAST SIZE 1B
J 0
(1975 900);
DISPLAY 0.872340 (1975 900);
PAINT GREEN (1975 900);
DISPLAY INVISIBLE (1975 900);
FORCEPROP 1 LAST BODY_TYPE PLUMBING
J 0
(1855 907);
DISPLAY 0.340426 (1855 907);
PAINT GREEN (1855 907);
DISPLAY INVISIBLE (1855 907);
FORCEPROP 1 LAST HDL_POWER GND
J 0
(1900 1100);
DISPLAY 0.872340 (1900 1100);
PAINT GREEN (1900 1100);
DISPLAY INVISIBLE (1900 1100);
FORCEADD GND..1
(1600 950);
FORCEPROP 3 LASTPIN (1600 1000) SIG_NAME GND\g
J 0
(1610 1010);
DISPLAY 0.659574 (1610 1010);
PAINT MONO (1610 1010);
DISPLAY INVISIBLE (1610 1010);
FORCEPROP 1 LAST SIZE 1B
J 0
(1675 900);
DISPLAY 0.872340 (1675 900);
PAINT GREEN (1675 900);
DISPLAY INVISIBLE (1675 900);
FORCEPROP 1 LAST VOLTAGE 0
J 0
(1600 950);
PAINT SKYBLUE (1600 950);
DISPLAY INVISIBLE (1600 950);
FORCEPROP 2 LAST ROOM PVPP_KLM_VR
J 0
(1025 1025);
DISPLAY 1.042553 (1025 1025);
PAINT GREEN (1025 1025);
DISPLAY INVISIBLE (1025 1025);
FORCEPROP 2 LAST BOM_COST PVPP_KLM_VR
J 0
(750 1025);
DISPLAY 1.042553 (750 1025);
PAINT WHITE (750 1025);
DISPLAY INVISIBLE (750 1025);
FORCEPROP 2 LAST CDS_LIB mstr_symbols
J 0
(1600 950);
PAINT MONO (1600 950);
DISPLAY INVISIBLE (1600 950);
FORCEPROP 1 LAST PATH I163
J 0
(1675 950);
DISPLAY 0.872340 (1675 950);
PAINT AQUA (1675 950);
DISPLAY INVISIBLE (1675 950);
FORCEPROP 1 LAST BODY_TYPE PLUMBING
J 0
(1555 907);
DISPLAY 0.340426 (1555 907);
PAINT GREEN (1555 907);
DISPLAY INVISIBLE (1555 907);
FORCEPROP 1 LAST HDL_POWER GND
J 0
(1600 1100);
DISPLAY 0.872340 (1600 1100);
PAINT GREEN (1600 1100);
DISPLAY INVISIBLE (1600 1100);
FORCEADD SC22U16V5MX-4-GP..1
(2950 1200);
FORCEPROP 2 LAST RATED 16V
J 0
(3050 1200);
DISPLAY 0.638298 (3050 1200);
PAINT GREEN (3050 1200);
FORCEPROP 2 LAST TYPE X6S
J 0
(3050 1150);
DISPLAY 0.638298 (3050 1150);
PAINT GREEN (3050 1150);
FORCEPROP 2 LAST PACK_SIZE 0805
J 0
(3050 1100);
DISPLAY 0.638298 (3050 1100);
PAINT GREEN (3050 1100);
FORCEPROP 2 LASTPIN (2950 1125) $PN 2
R 1
J 2
(2940 1115);
DISPLAY 0.808511 (2940 1115);
PAINT ORANGE (2940 1115);
FORCEPROP 2 LAST ATTRIBUTE 22UF
J 0
(3050 1300);
DISPLAY 0.638298 (3050 1300);
PAINT GREEN (3050 1300);
FORCEPROP 2 LAST TOLERANCE 20%
J 0
(3050 1250);
DISPLAY 0.638298 (3050 1250);
PAINT GREEN (3050 1250);
FORCEPROP 2 LASTPIN (2950 1275) $PN 1
R 1
J 0
(2940 1285);
DISPLAY 0.808511 (2940 1285);
PAINT ORANGE (2940 1285);
FORCEPROP 1 LAST VALUE SC22U16V5MX-4-GP
R 1
J 0
(3025 995);
DISPLAY 0.617021 (3025 995);
PAINT GREEN (3025 995);
FORCEPROP 1 LAST LOCATION C4E9
J 0
(3050 1360);
DISPLAY 0.617021 (3050 1360);
PAINT GREEN (3050 1360);
FORCEPROP 1 LAST PATH I164
J 0
(2950 1200);
DISPLAY 0.617021 (2950 1200);
PAINT GREEN (2950 1200);
DISPLAY INVISIBLE (2950 1200);
FORCEPROP 1 LAST PACK_TYPE SMD-BCG5
J 0
(2950 1200);
DISPLAY 0.617021 (2950 1200);
PAINT GREEN (2950 1200);
DISPLAY INVISIBLE (2950 1200);
FORCEPROP 2 LAST SEC 1
J 0
(2975 1275);
DISPLAY 0.680851 (2975 1275);
PAINT MONO (2975 1275);
DISPLAY INVISIBLE (2975 1275);
FORCEPROP 2 LAST SEC_TYPE SMD-BCG5
J 0
(2975 1275);
DISPLAY 1.021277 (2975 1275);
PAINT ORANGE (2975 1275);
DISPLAY INVISIBLE (2975 1275);
FORCEPROP 1 LAST PART_NUMBER 078.22611.0811
J 0
(2950 1200);
DISPLAY 0.617021 (2950 1200);
PAINT GREEN (2950 1200);
DISPLAY INVISIBLE (2950 1200);
FORCEPROP 2 LAST CDS_LIB w_hdl
J 0
(2950 1200);
PAINT MONO (2950 1200);
DISPLAY INVISIBLE (2950 1200);
FORCEPROP 1 LAST CDS_LMAN_SYM_OUTLINE -50,25,50,-25
J 0
(2950 1200);
DISPLAY 0.468085 (2950 1200);
PAINT GREEN (2950 1200);
DISPLAY INVISIBLE (2950 1200);
FORCEADD GND..1
(2950 950);
FORCEPROP 3 LASTPIN (2950 1000) SIG_NAME GND\g
J 0
(2960 1010);
DISPLAY 0.659574 (2960 1010);
PAINT MONO (2960 1010);
DISPLAY INVISIBLE (2960 1010);
FORCEPROP 1 LAST PATH I165
J 0
(3025 950);
DISPLAY 0.872340 (3025 950);
PAINT AQUA (3025 950);
DISPLAY INVISIBLE (3025 950);
FORCEPROP 2 LAST CDS_LIB mstr_symbols
J 0
(2950 950);
PAINT MONO (2950 950);
DISPLAY INVISIBLE (2950 950);
FORCEPROP 2 LAST BOM_COST PVPP_KLM_VR
J 0
(2100 1025);
DISPLAY 1.042553 (2100 1025);
PAINT WHITE (2100 1025);
DISPLAY INVISIBLE (2100 1025);
FORCEPROP 2 LAST ROOM PVPP_KLM_VR
J 0
(2375 1025);
DISPLAY 1.042553 (2375 1025);
PAINT GREEN (2375 1025);
DISPLAY INVISIBLE (2375 1025);
FORCEPROP 1 LAST VOLTAGE 0
J 0
(2950 950);
PAINT SKYBLUE (2950 950);
DISPLAY INVISIBLE (2950 950);
FORCEPROP 1 LAST SIZE 1B
J 0
(3025 900);
DISPLAY 0.872340 (3025 900);
PAINT GREEN (3025 900);
DISPLAY INVISIBLE (3025 900);
FORCEPROP 1 LAST BODY_TYPE PLUMBING
J 0
(2905 907);
DISPLAY 0.340426 (2905 907);
PAINT GREEN (2905 907);
DISPLAY INVISIBLE (2905 907);
FORCEPROP 1 LAST HDL_POWER GND
J 0
(2950 1100);
DISPLAY 0.872340 (2950 1100);
PAINT GREEN (2950 1100);
DISPLAY INVISIBLE (2950 1100);
FORCEADD SC22U16V5MX-4-GP..1
(3850 1200);
FORCEPROP 2 LASTPIN (3850 1275) $PN 1
R 1
J 0
(3840 1285);
DISPLAY 0.808511 (3840 1285);
PAINT ORANGE (3840 1285);
FORCEPROP 2 LASTPIN (3850 1125) $PN 2
R 1
J 2
(3840 1115);
DISPLAY 0.808511 (3840 1115);
PAINT ORANGE (3840 1115);
FORCEPROP 2 LAST PACK_SIZE 0805
J 0
(3950 1100);
DISPLAY 0.638298 (3950 1100);
PAINT GREEN (3950 1100);
FORCEPROP 2 LAST TYPE X6S
J 0
(3950 1150);
DISPLAY 0.638298 (3950 1150);
PAINT GREEN (3950 1150);
FORCEPROP 2 LAST RATED 16V
J 0
(3950 1200);
DISPLAY 0.638298 (3950 1200);
PAINT GREEN (3950 1200);
FORCEPROP 2 LAST TOLERANCE 20%
J 0
(3950 1250);
DISPLAY 0.638298 (3950 1250);
PAINT GREEN (3950 1250);
FORCEPROP 1 LAST VALUE SC22U16V5MX-4-GP
R 1
J 0
(3925 995);
DISPLAY 0.617021 (3925 995);
PAINT GREEN (3925 995);
FORCEPROP 1 LAST LOCATION C22W21
J 0
(3950 1360);
DISPLAY 0.617021 (3950 1360);
PAINT GREEN (3950 1360);
FORCEPROP 2 LAST ATTRIBUTE 22UF
J 0
(3950 1300);
DISPLAY 0.638298 (3950 1300);
PAINT GREEN (3950 1300);
FORCEPROP 1 LAST PACK_TYPE SMD-BCG5
J 0
(3850 1200);
DISPLAY 0.617021 (3850 1200);
PAINT GREEN (3850 1200);
DISPLAY INVISIBLE (3850 1200);
FORCEPROP 2 LAST SEC 1
J 0
(3875 1275);
DISPLAY 0.680851 (3875 1275);
PAINT MONO (3875 1275);
DISPLAY INVISIBLE (3875 1275);
FORCEPROP 2 LAST SEC_TYPE SMD-BCG5
J 0
(3875 1275);
DISPLAY 1.021277 (3875 1275);
PAINT ORANGE (3875 1275);
DISPLAY INVISIBLE (3875 1275);
FORCEPROP 1 LAST PART_NUMBER 078.22611.0811
J 0
(3850 1200);
DISPLAY 0.617021 (3850 1200);
PAINT GREEN (3850 1200);
DISPLAY INVISIBLE (3850 1200);
FORCEPROP 2 LAST CDS_LIB w_hdl
J 0
(3850 1200);
PAINT MONO (3850 1200);
DISPLAY INVISIBLE (3850 1200);
FORCEPROP 1 LAST CDS_LMAN_SYM_OUTLINE -50,25,50,-25
J 0
(3850 1200);
DISPLAY 0.468085 (3850 1200);
PAINT GREEN (3850 1200);
DISPLAY INVISIBLE (3850 1200);
FORCEPROP 1 LAST PATH I166
J 0
(3850 1200);
DISPLAY 0.617021 (3850 1200);
PAINT GREEN (3850 1200);
DISPLAY INVISIBLE (3850 1200);
FORCEADD GND..1
(3850 950);
FORCEPROP 3 LASTPIN (3850 1000) SIG_NAME GND\g
J 0
(3860 1010);
DISPLAY 0.659574 (3860 1010);
PAINT MONO (3860 1010);
DISPLAY INVISIBLE (3860 1010);
FORCEPROP 2 LAST CDS_LIB mstr_symbols
J 0
(3850 950);
PAINT MONO (3850 950);
DISPLAY INVISIBLE (3850 950);
FORCEPROP 2 LAST BOM_COST PVPP_KLM_VR
J 0
(3000 1025);
DISPLAY 1.042553 (3000 1025);
PAINT WHITE (3000 1025);
DISPLAY INVISIBLE (3000 1025);
FORCEPROP 2 LAST ROOM PVPP_KLM_VR
J 0
(3275 1025);
DISPLAY 1.042553 (3275 1025);
PAINT GREEN (3275 1025);
DISPLAY INVISIBLE (3275 1025);
FORCEPROP 1 LAST VOLTAGE 0
J 0
(3850 950);
PAINT SKYBLUE (3850 950);
DISPLAY INVISIBLE (3850 950);
FORCEPROP 1 LAST SIZE 1B
J 0
(3925 900);
DISPLAY 0.872340 (3925 900);
PAINT GREEN (3925 900);
DISPLAY INVISIBLE (3925 900);
FORCEPROP 1 LAST PATH I167
J 0
(3925 950);
DISPLAY 0.872340 (3925 950);
PAINT AQUA (3925 950);
DISPLAY INVISIBLE (3925 950);
FORCEPROP 1 LAST BODY_TYPE PLUMBING
J 0
(3805 907);
DISPLAY 0.340426 (3805 907);
PAINT GREEN (3805 907);
DISPLAY INVISIBLE (3805 907);
FORCEPROP 1 LAST HDL_POWER GND
J 0
(3850 1100);
DISPLAY 0.872340 (3850 1100);
PAINT GREEN (3850 1100);
DISPLAY INVISIBLE (3850 1100);
FORCEADD SC22U16V5MX-4-GP..1
(3550 1200);
FORCEPROP 1 LAST VALUE SC22U16V5MX-4-GP
R 1
J 0
(3625 995);
DISPLAY 0.617021 (3625 995);
PAINT GREEN (3625 995);
FORCEPROP 2 LAST TYPE X6S
J 0
(3650 1150);
DISPLAY 0.638298 (3650 1150);
PAINT GREEN (3650 1150);
FORCEPROP 2 LASTPIN (3550 1275) $PN 1
R 1
J 0
(3540 1285);
DISPLAY 0.808511 (3540 1285);
PAINT ORANGE (3540 1285);
FORCEPROP 2 LAST ATTRIBUTE 22UF
J 0
(3650 1300);
DISPLAY 0.638298 (3650 1300);
PAINT GREEN (3650 1300);
FORCEPROP 2 LAST TOLERANCE 20%
J 0
(3650 1250);
DISPLAY 0.638298 (3650 1250);
PAINT GREEN (3650 1250);
FORCEPROP 2 LAST RATED 16V
J 0
(3650 1200);
DISPLAY 0.638298 (3650 1200);
PAINT GREEN (3650 1200);
FORCEPROP 2 LAST PACK_SIZE 0805
J 0
(3650 1100);
DISPLAY 0.638298 (3650 1100);
PAINT GREEN (3650 1100);
FORCEPROP 2 LASTPIN (3550 1125) $PN 2
R 1
J 2
(3540 1115);
DISPLAY 0.808511 (3540 1115);
PAINT ORANGE (3540 1115);
FORCEPROP 1 LAST LOCATION C22W20
J 0
(3650 1360);
DISPLAY 0.617021 (3650 1360);
PAINT GREEN (3650 1360);
FORCEPROP 1 LAST PACK_TYPE SMD-BCG5
J 0
(3550 1200);
DISPLAY 0.617021 (3550 1200);
PAINT GREEN (3550 1200);
DISPLAY INVISIBLE (3550 1200);
FORCEPROP 2 LAST SEC 1
J 0
(3575 1275);
DISPLAY 0.680851 (3575 1275);
PAINT MONO (3575 1275);
DISPLAY INVISIBLE (3575 1275);
FORCEPROP 2 LAST SEC_TYPE SMD-BCG5
J 0
(3575 1275);
DISPLAY 1.021277 (3575 1275);
PAINT ORANGE (3575 1275);
DISPLAY INVISIBLE (3575 1275);
FORCEPROP 1 LAST PART_NUMBER 078.22611.0811
J 0
(3550 1200);
DISPLAY 0.617021 (3550 1200);
PAINT GREEN (3550 1200);
DISPLAY INVISIBLE (3550 1200);
FORCEPROP 2 LAST CDS_LIB w_hdl
J 0
(3550 1200);
PAINT MONO (3550 1200);
DISPLAY INVISIBLE (3550 1200);
FORCEPROP 1 LAST CDS_LMAN_SYM_OUTLINE -50,25,50,-25
J 0
(3550 1200);
DISPLAY 0.468085 (3550 1200);
PAINT GREEN (3550 1200);
DISPLAY INVISIBLE (3550 1200);
FORCEPROP 1 LAST PATH I168
J 0
(3550 1200);
DISPLAY 0.617021 (3550 1200);
PAINT GREEN (3550 1200);
DISPLAY INVISIBLE (3550 1200);
FORCEADD SC22U16V5MX-4-GP..1
(3250 1200);
FORCEPROP 2 LAST PACK_SIZE 0805
J 0
(3350 1100);
DISPLAY 0.638298 (3350 1100);
PAINT GREEN (3350 1100);
FORCEPROP 2 LAST TYPE X6S
J 0
(3350 1150);
DISPLAY 0.638298 (3350 1150);
PAINT GREEN (3350 1150);
FORCEPROP 2 LASTPIN (3250 1125) $PN 2
R 1
J 2
(3240 1115);
DISPLAY 0.808511 (3240 1115);
PAINT ORANGE (3240 1115);
FORCEPROP 2 LAST TOLERANCE 20%
J 0
(3350 1250);
DISPLAY 0.638298 (3350 1250);
PAINT GREEN (3350 1250);
FORCEPROP 2 LAST RATED 16V
J 0
(3350 1200);
DISPLAY 0.638298 (3350 1200);
PAINT GREEN (3350 1200);
FORCEPROP 2 LAST ATTRIBUTE 22UF
J 0
(3350 1300);
DISPLAY 0.638298 (3350 1300);
PAINT GREEN (3350 1300);
FORCEPROP 1 LAST LOCATION C22W19
J 0
(3350 1360);
DISPLAY 0.617021 (3350 1360);
PAINT GREEN (3350 1360);
FORCEPROP 1 LAST VALUE SC22U16V5MX-4-GP
R 1
J 0
(3325 995);
DISPLAY 0.617021 (3325 995);
PAINT GREEN (3325 995);
FORCEPROP 2 LASTPIN (3250 1275) $PN 1
R 1
J 0
(3240 1285);
DISPLAY 0.808511 (3240 1285);
PAINT ORANGE (3240 1285);
FORCEPROP 1 LAST PACK_TYPE SMD-BCG5
J 0
(3250 1200);
DISPLAY 0.617021 (3250 1200);
PAINT GREEN (3250 1200);
DISPLAY INVISIBLE (3250 1200);
FORCEPROP 2 LAST SEC 1
J 0
(3275 1275);
DISPLAY 0.680851 (3275 1275);
PAINT MONO (3275 1275);
DISPLAY INVISIBLE (3275 1275);
FORCEPROP 2 LAST SEC_TYPE SMD-BCG5
J 0
(3275 1275);
DISPLAY 1.021277 (3275 1275);
PAINT ORANGE (3275 1275);
DISPLAY INVISIBLE (3275 1275);
FORCEPROP 1 LAST PART_NUMBER 078.22611.0811
J 0
(3250 1200);
DISPLAY 0.617021 (3250 1200);
PAINT GREEN (3250 1200);
DISPLAY INVISIBLE (3250 1200);
FORCEPROP 2 LAST CDS_LIB w_hdl
J 0
(3250 1200);
PAINT MONO (3250 1200);
DISPLAY INVISIBLE (3250 1200);
FORCEPROP 1 LAST CDS_LMAN_SYM_OUTLINE -50,25,50,-25
J 0
(3250 1200);
DISPLAY 0.468085 (3250 1200);
PAINT GREEN (3250 1200);
DISPLAY INVISIBLE (3250 1200);
FORCEPROP 1 LAST PATH I169
J 0
(3250 1200);
DISPLAY 0.617021 (3250 1200);
PAINT GREEN (3250 1200);
DISPLAY INVISIBLE (3250 1200);
FORCEADD GND..1
(3550 950);
FORCEPROP 3 LASTPIN (3550 1000) SIG_NAME GND\g
J 0
(3560 1010);
DISPLAY 0.659574 (3560 1010);
PAINT MONO (3560 1010);
DISPLAY INVISIBLE (3560 1010);
FORCEPROP 1 LAST SIZE 1B
J 0
(3625 900);
DISPLAY 0.872340 (3625 900);
PAINT GREEN (3625 900);
DISPLAY INVISIBLE (3625 900);
FORCEPROP 1 LAST VOLTAGE 0
J 0
(3550 950);
PAINT SKYBLUE (3550 950);
DISPLAY INVISIBLE (3550 950);
FORCEPROP 2 LAST ROOM PVPP_KLM_VR
J 0
(2975 1025);
DISPLAY 1.042553 (2975 1025);
PAINT GREEN (2975 1025);
DISPLAY INVISIBLE (2975 1025);
FORCEPROP 2 LAST BOM_COST PVPP_KLM_VR
J 0
(2700 1025);
DISPLAY 1.042553 (2700 1025);
PAINT WHITE (2700 1025);
DISPLAY INVISIBLE (2700 1025);
FORCEPROP 2 LAST CDS_LIB mstr_symbols
J 0
(3550 950);
PAINT MONO (3550 950);
DISPLAY INVISIBLE (3550 950);
FORCEPROP 1 LAST PATH I170
J 0
(3625 950);
DISPLAY 0.872340 (3625 950);
PAINT AQUA (3625 950);
DISPLAY INVISIBLE (3625 950);
FORCEPROP 1 LAST BODY_TYPE PLUMBING
J 0
(3505 907);
DISPLAY 0.340426 (3505 907);
PAINT GREEN (3505 907);
DISPLAY INVISIBLE (3505 907);
FORCEPROP 1 LAST HDL_POWER GND
J 0
(3550 1100);
DISPLAY 0.872340 (3550 1100);
PAINT GREEN (3550 1100);
DISPLAY INVISIBLE (3550 1100);
FORCEADD GND..1
(3250 950);
FORCEPROP 3 LASTPIN (3250 1000) SIG_NAME GND\g
J 0
(3260 1010);
DISPLAY 0.659574 (3260 1010);
PAINT MONO (3260 1010);
DISPLAY INVISIBLE (3260 1010);
FORCEPROP 1 LAST SIZE 1B
J 0
(3325 900);
DISPLAY 0.872340 (3325 900);
PAINT GREEN (3325 900);
DISPLAY INVISIBLE (3325 900);
FORCEPROP 1 LAST VOLTAGE 0
J 0
(3250 950);
PAINT SKYBLUE (3250 950);
DISPLAY INVISIBLE (3250 950);
FORCEPROP 2 LAST ROOM PVPP_KLM_VR
J 0
(2675 1025);
DISPLAY 1.042553 (2675 1025);
PAINT GREEN (2675 1025);
DISPLAY INVISIBLE (2675 1025);
FORCEPROP 2 LAST BOM_COST PVPP_KLM_VR
J 0
(2400 1025);
DISPLAY 1.042553 (2400 1025);
PAINT WHITE (2400 1025);
DISPLAY INVISIBLE (2400 1025);
FORCEPROP 2 LAST CDS_LIB mstr_symbols
J 0
(3250 950);
PAINT MONO (3250 950);
DISPLAY INVISIBLE (3250 950);
FORCEPROP 1 LAST PATH I171
J 0
(3325 950);
DISPLAY 0.872340 (3325 950);
PAINT AQUA (3325 950);
DISPLAY INVISIBLE (3325 950);
FORCEPROP 1 LAST BODY_TYPE PLUMBING
J 0
(3205 907);
DISPLAY 0.340426 (3205 907);
PAINT GREEN (3205 907);
DISPLAY INVISIBLE (3205 907);
FORCEPROP 1 LAST HDL_POWER GND
J 0
(3250 1100);
DISPLAY 0.872340 (3250 1100);
PAINT GREEN (3250 1100);
DISPLAY INVISIBLE (3250 1100);
FORCEADD UNIVERSAL_POWER..1
(3850 1650);
FORCEPROP 3 LASTPIN (3850 1600) SIG_NAME VR_FET_SW_P12V_STBY_PVCCIN_CPU0\g
J 0
(3860 1610);
DISPLAY 0.659574 (3860 1610);
PAINT MONO (3860 1610);
DISPLAY INVISIBLE (3860 1610);
FORCEPROP 1 LAST HDL_POWER VR_FET_SW_P12V_STBY_PVCCIN_CPU0
J 1
(3825 1700);
DISPLAY 0.617021 (3825 1700);
PAINT GREEN (3825 1700);
FORCEPROP 2 LAST CDS_LIB mstr_symbols
J 0
(3850 1650);
PAINT ORANGE (3850 1650);
DISPLAY INVISIBLE (3850 1650);
FORCEPROP 1 LAST PATH I172
J 0
(3900 1675);
DISPLAY 0.872340 (3900 1675);
PAINT AQUA (3900 1675);
DISPLAY INVISIBLE (3900 1675);
FORCEADD RES..1
(-1575 4750);
FORCEPROP 1 LAST WATTAGE 1/16W
J 2
(-1225 4800);
DISPLAY 0.510638 (-1225 4800);
PAINT SKYBLUE (-1225 4800);
FORCEPROP 1 LASTPIN (-1675 4750) $PN 1
J 0
(-1663 4762);
DISPLAY 0.617021 (-1663 4762);
PAINT WHITE (-1663 4762);
FORCEPROP 1 LAST VALUE 0.0
J 2
(-1675 4650);
DISPLAY 0.617021 (-1675 4650);
PAINT SKYBLUE (-1675 4650);
FORCEPROP 1 LASTPIN (-1475 4750) $PN 2
J 0
(-1513 4762);
DISPLAY 0.617021 (-1513 4762);
PAINT WHITE (-1513 4762);
FORCEPROP 1 LAST LOCATION R6R5
J 0
(-1675 4800);
DISPLAY 0.617021 (-1675 4800);
PAINT AQUA (-1675 4800);
FORCEPROP 1 LAST TOLERANCE 5%
J 0
(-1625 4650);
DISPLAY 0.617021 (-1625 4650);
PAINT SKYBLUE (-1625 4650);
FORCEPROP 1 LAST PART_NUMBER G21497-005
J 0
(-1700 4700);
DISPLAY 0.617021 (-1700 4700);
PAINT BLUE (-1700 4700);
FORCEPROP 1 LAST PACK_TYPE 0402
J 0
(-1500 4650);
DISPLAY 0.617021 (-1500 4650);
PAINT SKYBLUE (-1500 4650);
FORCEPROP 1 LAST MATERIAL CHIP
J 0
(-1325 4650);
DISPLAY 0.510638 (-1325 4650);
PAINT SKYBLUE (-1325 4650);
FORCEPROP 2 LAST CDS_LOCATION R6R5
J 0
(-2050 4750);
DISPLAY 0.617021 (-2050 4750);
PAINT AQUA (-2050 4750);
DISPLAY INVISIBLE (-2050 4750);
FORCEPROP 1 LAST PATH I173
J 0
(-1625 4900);
DISPLAY 0.978723 (-1625 4900);
PAINT WHITE (-1625 4900);
DISPLAY INVISIBLE (-1625 4900);
FORCEPROP 0 LAST CDS_SEC 1
J 0
(-1275 4800);
PAINT MONO (-1275 4800);
DISPLAY INVISIBLE (-1275 4800);
FORCEPROP 2 LAST ROOM CPU0
J 0
(-1625 4900);
PAINT PEACH (-1625 4900);
DISPLAY INVISIBLE (-1625 4900);
FORCEPROP 2 LAST SEC 1
J 0
(-1625 4975);
DISPLAY 0.680851 (-1625 4975);
PAINT MONO (-1625 4975);
DISPLAY INVISIBLE (-1625 4975);
FORCEPROP 2 LAST SEC_TYPE 0402
J 0
(-1625 4975);
DISPLAY 1.021277 (-1625 4975);
PAINT ORANGE (-1625 4975);
DISPLAY INVISIBLE (-1625 4975);
FORCEPROP 2 LAST CDS_LIB mstr_discrete
J 0
(-1575 4750);
DISPLAY 1.340426 (-1575 4750);
PAINT ORANGE (-1575 4750);
DISPLAY INVISIBLE (-1575 4750);
FORCEPROP 2 LAST BOM_COST PROC_SIDEBAND
J 0
(-1575 4750);
PAINT MONO (-1575 4750);
DISPLAY INVISIBLE (-1575 4750);
FORCEADD IND-150NH-56-GP..1
R 1
(3000 3650);
FORCEPROP 2 LAST TYPE IRMS=66A@DELTA_T<40C
J 0
(2825 3425);
DISPLAY 0.638298 (2825 3425);
PAINT GREEN (2825 3425);
FORCEPROP 1 LAST LOCATION L4E2
J 0
(2845 3695);
DISPLAY 0.617021 (2845 3695);
PAINT GREEN (2845 3695);
FORCEPROP 2 LASTPIN (2850 3625) $PN 1
J 2
(2840 3635);
DISPLAY 0.808511 (2840 3635);
PAINT ORANGE (2840 3635);
FORCEPROP 2 LASTPIN (3150 3625) $PN 2
J 0
(3160 3635);
DISPLAY 0.808511 (3160 3635);
PAINT ORANGE (3160 3635);
FORCEPROP 1 LAST VALUE IND-150NH-56-GP
J 0
(2825 3575);
DISPLAY 0.617021 (2825 3575);
PAINT GREEN (2825 3575);
FORCEPROP 2 LAST ATTRIBUTE 150NH
J 0
(2825 3525);
DISPLAY 0.638298 (2825 3525);
PAINT GREEN (2825 3525);
FORCEPROP 2 LAST RATED ISAT=75A@25C
J 0
(2825 3475);
DISPLAY 0.638298 (2825 3475);
PAINT GREEN (2825 3475);
FORCEPROP 2 LAST PACK_SIZE DCR=0.17MOHM
J 0
(2825 3375);
DISPLAY 0.638298 (2825 3375);
PAINT GREEN (2825 3375);
FORCEPROP 1 LAST PATH I174
R 1
J 0
(3000 3650);
DISPLAY 0.617021 (3000 3650);
PAINT GREEN (3000 3650);
DISPLAY INVISIBLE (3000 3650);
FORCEPROP 1 LAST PART_NUMBER 068.1512N.M001
R 1
J 0
(3000 3650);
DISPLAY 0.617021 (3000 3650);
PAINT GREEN (3000 3650);
DISPLAY INVISIBLE (3000 3650);
FORCEPROP 2 LAST CDS_LIB w_hdl
R 1
J 0
(3000 3650);
PAINT MONO (3000 3650);
DISPLAY INVISIBLE (3000 3650);
FORCEPROP 1 LAST CDS_LMAN_SYM_OUTLINE -75,100,75,-100
R 1
J 0
(3000 3650);
DISPLAY 0.468085 (3000 3650);
PAINT GREEN (3000 3650);
DISPLAY INVISIBLE (3000 3650);
FORCEPROP 2 LAST SEC_TYPE DISCRET-GA1
J 0
(3150 3725);
DISPLAY 1.021277 (3150 3725);
PAINT ORANGE (3150 3725);
DISPLAY INVISIBLE (3150 3725);
FORCEPROP 2 LAST SEC 1
J 0
(3150 3725);
DISPLAY 0.680851 (3150 3725);
PAINT MONO (3150 3725);
DISPLAY INVISIBLE (3150 3725);
FORCEPROP 1 LAST PACK_TYPE DISCRET-GA1
R 1
J 0
(3000 3650);
DISPLAY 0.617021 (3000 3650);
PAINT GREEN (3000 3650);
DISPLAY INVISIBLE (3000 3650);
FORCEADD SC1U10V2KX-4-GP..1
(-1350 4175);
FORCEPROP 2 LASTPIN (-1350 4100) $PN 2
R 1
J 2
(-1360 4090);
DISPLAY 0.808511 (-1360 4090);
PAINT ORANGE (-1360 4090);
FORCEPROP 1 LAST LOCATION C4E28
J 0
(-1225 4255);
DISPLAY 0.617021 (-1225 4255);
PAINT GREEN (-1225 4255);
FORCEPROP 1 LAST VALUE SC1U10V2KX-4-GP
R 1
J 0
(-1250 3975);
DISPLAY 0.617021 (-1250 3975);
PAINT GREEN (-1250 3975);
FORCEPROP 2 LASTPIN (-1350 4250) $PN 1
R 1
J 0
(-1360 4260);
DISPLAY 0.808511 (-1360 4260);
PAINT ORANGE (-1360 4260);
FORCEPROP 2 LAST ATTRIBUTE 1UF
J 0
(-1225 4200);
DISPLAY 0.638298 (-1225 4200);
PAINT GREEN (-1225 4200);
FORCEPROP 2 LAST TOLERANCE 10%
J 0
(-1225 4150);
DISPLAY 0.638298 (-1225 4150);
PAINT GREEN (-1225 4150);
FORCEPROP 2 LAST RATED 10V
J 0
(-1225 4100);
DISPLAY 0.638298 (-1225 4100);
PAINT GREEN (-1225 4100);
FORCEPROP 2 LAST PACK_SIZE 0402
J 0
(-1225 4050);
DISPLAY 0.638298 (-1225 4050);
PAINT GREEN (-1225 4050);
FORCEPROP 1 LAST PART_NUMBER 78.10523.8FL
J 0
(-1350 4175);
DISPLAY 0.617021 (-1350 4175);
PAINT GREEN (-1350 4175);
DISPLAY INVISIBLE (-1350 4175);
FORCEPROP 2 LAST CDS_LIB w_hdl
J 0
(-1350 4175);
PAINT MONO (-1350 4175);
DISPLAY INVISIBLE (-1350 4175);
FORCEPROP 1 LAST PATH I175
J 0
(-1350 4175);
DISPLAY 0.617021 (-1350 4175);
PAINT GREEN (-1350 4175);
DISPLAY INVISIBLE (-1350 4175);
FORCEPROP 1 LAST CDS_LMAN_SYM_OUTLINE -50,25,50,-25
J 0
(-1350 4175);
DISPLAY 0.468085 (-1350 4175);
PAINT GREEN (-1350 4175);
DISPLAY INVISIBLE (-1350 4175);
FORCEPROP 2 LAST SEC_TYPE SMD-BCG6
J 0
(-1325 4250);
DISPLAY 1.021277 (-1325 4250);
PAINT ORANGE (-1325 4250);
DISPLAY INVISIBLE (-1325 4250);
FORCEPROP 2 LAST SEC 1
J 0
(-1325 4250);
DISPLAY 0.680851 (-1325 4250);
PAINT MONO (-1325 4250);
DISPLAY INVISIBLE (-1325 4250);
FORCEPROP 1 LAST PACK_TYPE SMD-BCG6
J 0
(-1350 4175);
DISPLAY 0.617021 (-1350 4175);
PAINT GREEN (-1350 4175);
DISPLAY INVISIBLE (-1350 4175);
FORCEADD 1R3F-GP..1
(2200 3100);
FORCEPROP 2 LAST RATED 1/10W
J 0
(2250 3025);
DISPLAY 0.638298 (2250 3025);
PAINT GREEN (2250 3025);
FORCEPROP 2 LAST PACK_SIZE 0603
J 0
(2250 2975);
DISPLAY 0.638298 (2250 2975);
PAINT GREEN (2250 2975);
FORCEPROP 1 LAST LOCATION RT42
J 0
(2250 3225);
DISPLAY 0.617021 (2250 3225);
PAINT GREEN (2250 3225);
FORCEPROP 1 LAST VALUE 1R3F-GP
J 0
(2250 3175);
DISPLAY 0.617021 (2250 3175);
PAINT GREEN (2250 3175);
FORCEPROP 2 LAST TOLERANCE 1%
J 0
(2250 3075);
DISPLAY 0.638298 (2250 3075);
PAINT GREEN (2250 3075);
FORCEPROP 2 LASTPIN (2200 3225) $PN 1
R 1
J 0
(2190 3235);
DISPLAY 0.808511 (2190 3235);
PAINT ORANGE (2190 3235);
FORCEPROP 2 LASTPIN (2200 2975) $PN 2
R 1
J 2
(2190 2965);
DISPLAY 0.808511 (2190 2965);
PAINT ORANGE (2190 2965);
FORCEPROP 2 LAST ATTRIBUTE 1 OHM
J 0
(2250 3125);
DISPLAY 0.638298 (2250 3125);
PAINT GREEN (2250 3125);
FORCEPROP 0 LAST POP NOPOP
J 0
(2250 2925);
DISPLAY 0.638298 (2250 2925);
PAINT RED (2250 2925);
FORCEPROP 1 LAST PATH I176
J 0
(2200 3100);
DISPLAY 0.617021 (2200 3100);
PAINT GREEN (2200 3100);
DISPLAY INVISIBLE (2200 3100);
FORCEPROP 1 LAST CDS_LMAN_SYM_OUTLINE -50,75,50,-75
J 0
(2200 3100);
DISPLAY 0.468085 (2200 3100);
PAINT GREEN (2200 3100);
DISPLAY INVISIBLE (2200 3100);
FORCEPROP 2 LAST CDS_LIB w_hdl
J 0
(2200 3100);
DISPLAY INVISIBLE (2200 3100);
FORCEPROP 1 LAST PART_NUMBER 64.1R005.55L
J 0
(2200 3100);
DISPLAY 0.617021 (2200 3100);
PAINT GREEN (2200 3100);
DISPLAY INVISIBLE (2200 3100);
FORCEPROP 2 LAST SEC_TYPE RCL_GP
J 0
(2250 3200);
DISPLAY 1.021277 (2250 3200);
PAINT ORANGE (2250 3200);
DISPLAY INVISIBLE (2250 3200);
FORCEPROP 2 LAST SEC 1
J 0
(2250 3200);
DISPLAY 0.680851 (2250 3200);
PAINT MONO (2250 3200);
DISPLAY INVISIBLE (2250 3200);
FORCEPROP 1 LAST PACK_TYPE RCL_GP
J 0
(2200 3100);
DISPLAY 0.617021 (2200 3100);
PAINT GREEN (2200 3100);
DISPLAY INVISIBLE (2200 3100);
FORCEADD CAPP..1
R 2
(2650 2300);
FORCEPROP 0 LAST GROUP PWR_BULK_CAP
J 0
(2692 2080);
DISPLAY 0.638298 (2692 2080);
PAINT BROWN (2692 2080);
DISPLAY BOTH (2692 2080);
FORCEPROP 1 LASTPIN (2650 2400) $PN 1
J 2
(2640 2385);
DISPLAY 0.617021 (2640 2385);
PAINT WHITE (2640 2385);
FORCEPROP 1 LAST MATERIAL ALUM
J 0
(2700 2225);
DISPLAY 0.617021 (2700 2225);
PAINT SKYBLUE (2700 2225);
FORCEPROP 1 LAST PART_NUMBER 699013-049
J 0
(2700 2175);
DISPLAY 0.617021 (2700 2175);
PAINT BLUE (2700 2175);
FORCEPROP 1 LAST PACK_TYPE 3018
J 0
(2700 2125);
DISPLAY 0.617021 (2700 2125);
PAINT SKYBLUE (2700 2125);
FORCEPROP 1 LAST LOCATION C6R12
J 0
(2700 2425);
DISPLAY 0.617021 (2700 2425);
PAINT AQUA (2700 2425);
FORCEPROP 1 LAST VALUE 470UF
J 0
(2700 2375);
DISPLAY 0.617021 (2700 2375);
PAINT SKYBLUE (2700 2375);
FORCEPROP 1 LAST TOLERANCE 20%
J 0
(2700 2325);
DISPLAY 0.617021 (2700 2325);
PAINT SKYBLUE (2700 2325);
FORCEPROP 1 LAST VOLTAGE 2.5V
J 0
(2700 2275);
DISPLAY 0.617021 (2700 2275);
PAINT SKYBLUE (2700 2275);
FORCEPROP 1 LASTPIN (2650 2200) $PN 2
J 2
(2640 2185);
DISPLAY 0.617021 (2640 2185);
PAINT WHITE (2640 2185);
FORCEPROP 1 LAST PATH I177
J 2
(2600 2450);
DISPLAY 0.978723 (2600 2450);
PAINT ORANGE (2600 2450);
DISPLAY INVISIBLE (2600 2450);
FORCEPROP 2 LAST CDS_LIB mstr_discrete
J 0
(2650 2300);
PAINT ORANGE (2650 2300);
DISPLAY INVISIBLE (2650 2300);
FORCEPROP 2 LAST SEC_TYPE 3018
J 0
(2610 2515);
DISPLAY 1.021277 (2610 2515);
PAINT ORANGE (2610 2515);
DISPLAY INVISIBLE (2610 2515);
FORCEPROP 2 LAST SEC 1
J 0
(2610 2515);
DISPLAY 0.680851 (2610 2515);
PAINT MONO (2610 2515);
DISPLAY INVISIBLE (2610 2515);
FORCEPROP 2 LAST ROOM PVCCIO_CPU1
J 0
(2600 2425);
PAINT MONO (2600 2425);
DISPLAY INVISIBLE (2600 2425);
FORCEPROP 2 LAST BOM_COST PROC_VRD_PVCCIO_CPU1
J 0
(2600 2450);
PAINT MONO (2600 2450);
DISPLAY INVISIBLE (2600 2450);
FORCEPROP 2 LAST CDS_LOCATION C6R12
J 2
(2600 2400);
DISPLAY 0.617021 (2600 2400);
PAINT AQUA (2600 2400);
DISPLAY INVISIBLE (2600 2400);
FORCEADD CAPP..1
R 2
(3200 2300);
FORCEPROP 0 LAST GROUP PWR_BULK_CAP
J 0
(3242 2080);
DISPLAY 0.638298 (3242 2080);
PAINT BROWN (3242 2080);
DISPLAY BOTH (3242 2080);
FORCEPROP 1 LASTPIN (3200 2200) $PN 2
J 2
(3190 2185);
DISPLAY 0.617021 (3190 2185);
PAINT WHITE (3190 2185);
FORCEPROP 1 LASTPIN (3200 2400) $PN 1
J 2
(3190 2385);
DISPLAY 0.617021 (3190 2385);
PAINT WHITE (3190 2385);
FORCEPROP 1 LAST MATERIAL ALUM
J 0
(3250 2225);
DISPLAY 0.617021 (3250 2225);
PAINT SKYBLUE (3250 2225);
FORCEPROP 1 LAST VOLTAGE 2.5V
J 0
(3250 2275);
DISPLAY 0.617021 (3250 2275);
PAINT SKYBLUE (3250 2275);
FORCEPROP 1 LAST PART_NUMBER 699013-049
J 0
(3250 2175);
DISPLAY 0.617021 (3250 2175);
PAINT BLUE (3250 2175);
FORCEPROP 1 LAST PACK_TYPE 3018
J 0
(3250 2125);
DISPLAY 0.617021 (3250 2125);
PAINT SKYBLUE (3250 2125);
FORCEPROP 1 LAST TOLERANCE 20%
J 0
(3250 2325);
DISPLAY 0.617021 (3250 2325);
PAINT SKYBLUE (3250 2325);
FORCEPROP 1 LAST VALUE 470UF
J 0
(3250 2375);
DISPLAY 0.617021 (3250 2375);
PAINT SKYBLUE (3250 2375);
FORCEPROP 1 LAST LOCATION C4E7
J 0
(3250 2425);
DISPLAY 0.617021 (3250 2425);
PAINT AQUA (3250 2425);
FORCEPROP 2 LAST CDS_LIB mstr_discrete
J 0
(3200 2300);
PAINT ORANGE (3200 2300);
DISPLAY INVISIBLE (3200 2300);
FORCEPROP 2 LAST SEC_TYPE 3018
J 0
(3160 2515);
DISPLAY 1.021277 (3160 2515);
PAINT ORANGE (3160 2515);
DISPLAY INVISIBLE (3160 2515);
FORCEPROP 2 LAST SEC 1
J 0
(3160 2515);
DISPLAY 0.680851 (3160 2515);
PAINT MONO (3160 2515);
DISPLAY INVISIBLE (3160 2515);
FORCEPROP 2 LAST ROOM PVCCIO_CPU1
J 0
(3150 2425);
PAINT MONO (3150 2425);
DISPLAY INVISIBLE (3150 2425);
FORCEPROP 2 LAST BOM_COST PROC_VRD_PVCCIO_CPU1
J 0
(3150 2450);
PAINT MONO (3150 2450);
DISPLAY INVISIBLE (3150 2450);
FORCEPROP 1 LAST PATH I178
J 2
(3150 2450);
DISPLAY 0.978723 (3150 2450);
PAINT ORANGE (3150 2450);
DISPLAY INVISIBLE (3150 2450);
FORCEPROP 2 LAST CDS_LOCATION C4E7
J 2
(3150 2400);
DISPLAY 0.617021 (3150 2400);
PAINT AQUA (3150 2400);
DISPLAY INVISIBLE (3150 2400);
FORCEADD CAPP..1
R 2
(2100 2300);
FORCEPROP 1 LASTPIN (2100 2200) $PN 2
J 2
(2090 2185);
DISPLAY 0.617021 (2090 2185);
PAINT WHITE (2090 2185);
FORCEPROP 1 LASTPIN (2100 2400) $PN 1
J 2
(2090 2385);
DISPLAY 0.617021 (2090 2385);
PAINT WHITE (2090 2385);
FORCEPROP 1 LAST MATERIAL ALUM
J 0
(2150 2225);
DISPLAY 0.617021 (2150 2225);
PAINT SKYBLUE (2150 2225);
FORCEPROP 1 LAST VOLTAGE 2.5V
J 0
(2150 2275);
DISPLAY 0.617021 (2150 2275);
PAINT SKYBLUE (2150 2275);
FORCEPROP 1 LAST PART_NUMBER 699013-049
J 0
(2150 2175);
DISPLAY 0.617021 (2150 2175);
PAINT BLUE (2150 2175);
FORCEPROP 1 LAST LOCATION C6R5
J 0
(2150 2425);
DISPLAY 0.617021 (2150 2425);
PAINT AQUA (2150 2425);
FORCEPROP 1 LAST PACK_TYPE 3018
J 0
(2150 2125);
DISPLAY 0.617021 (2150 2125);
PAINT SKYBLUE (2150 2125);
FORCEPROP 1 LAST TOLERANCE 20%
J 0
(2150 2325);
DISPLAY 0.617021 (2150 2325);
PAINT SKYBLUE (2150 2325);
FORCEPROP 1 LAST VALUE 470UF
J 0
(2150 2375);
DISPLAY 0.617021 (2150 2375);
PAINT SKYBLUE (2150 2375);
FORCEPROP 0 LAST GROUP PWR_BULK_CAP
J 0
(2142 2080);
DISPLAY 0.638298 (2142 2080);
PAINT BROWN (2142 2080);
DISPLAY BOTH (2142 2080);
FORCEPROP 1 LAST PATH I24
J 0
(2050 2450);
DISPLAY 0.978723 (2050 2450);
PAINT ORANGE (2050 2450);
DISPLAY INVISIBLE (2050 2450);
FORCEPROP 2 LAST CDS_LIB mstr_discrete
J 0
(2100 2300);
PAINT ORANGE (2100 2300);
DISPLAY INVISIBLE (2100 2300);
FORCEPROP 2 LAST CDS_LOCATION C6R5
J 2
(2050 2400);
DISPLAY 0.617021 (2050 2400);
PAINT AQUA (2050 2400);
DISPLAY INVISIBLE (2050 2400);
FORCEPROP 2 LAST SEC_TYPE 3018
J 0
(2060 2515);
DISPLAY 1.021277 (2060 2515);
PAINT ORANGE (2060 2515);
DISPLAY INVISIBLE (2060 2515);
FORCEPROP 2 LAST SEC 1
J 0
(2060 2515);
DISPLAY 0.680851 (2060 2515);
PAINT MONO (2060 2515);
DISPLAY INVISIBLE (2060 2515);
FORCEPROP 2 LAST ROOM PVCCIO_CPU1
J 0
(2050 2425);
PAINT MONO (2050 2425);
DISPLAY INVISIBLE (2050 2425);
FORCEPROP 2 LAST BOM_COST PROC_VRD_PVCCIO_CPU1
J 0
(2050 2450);
PAINT MONO (2050 2450);
DISPLAY INVISIBLE (2050 2450);
FORCEADD PVCCIO_CPU1..1
(2100 2600);
FORCEPROP 3 LASTPIN (2100 2550) SIG_NAME PVCCIO_CPU1\g
J 0
(2110 2560);
DISPLAY 0.659574 (2110 2560);
PAINT MONO (2110 2560);
DISPLAY INVISIBLE (2110 2560);
FORCEPROP 1 LAST PATH I3
J 0
(2150 2625);
DISPLAY 0.872340 (2150 2625);
PAINT AQUA (2150 2625);
DISPLAY INVISIBLE (2150 2625);
FORCEPROP 2 LAST CDS_LIB mstr_symbols
J 0
(2100 2600);
PAINT ORANGE (2100 2600);
DISPLAY INVISIBLE (2100 2600);
FORCEPROP 1 LAST VOLTAGE 1.1V
J 0
(2055 2557);
DISPLAY 0.340426 (2055 2557);
PAINT SKYBLUE (2055 2557);
DISPLAY INVISIBLE (2055 2557);
FORCEPROP 1 LAST BODY_TYPE PLUMBING
J 0
(2055 2557);
DISPLAY 0.340426 (2055 2557);
PAINT GREEN (2055 2557);
DISPLAY INVISIBLE (2055 2557);
FORCEPROP 1 LAST HDL_POWER PVCCIO_CPU1
J 1
(2100 2650);
DISPLAY 0.872340 (2100 2650);
PAINT GREEN (2100 2650);
DISPLAY INVISIBLE (2100 2650);
FORCEADD OFFPAGE..2
(2725 4125);
FORCEPROP 2 LAST $XR0 213 
J 0
(2914 4125);
DISPLAY 0.638298 (2914 4125);
PAINT MONO (2914 4125);
FORCEPROP 2 LAST PATH I58
J 0
(2900 4200);
DISPLAY 1.021277 (2900 4200);
PAINT ORANGE (2900 4200);
DISPLAY INVISIBLE (2900 4200);
FORCEPROP 2 LAST BOM_COST PROC_VRD_PVCCIO_CPU1
J 0
(2925 4175);
DISPLAY 2.340426 (2925 4175);
PAINT WHITE (2925 4175);
DISPLAY INVISIBLE (2925 4175);
FORCEPROP 2 LAST ROOM PVCCIO_CPU1
J 0
(2325 4200);
DISPLAY 3.127660 (2325 4200);
PAINT WHITE (2325 4200);
DISPLAY INVISIBLE (2325 4200);
FORCEPROP 2 LAST CDS_LIB mstr_standard
J 0
(2725 4125);
DISPLAY 1.617021 (2725 4125);
PAINT ORANGE (2725 4125);
DISPLAY INVISIBLE (2725 4125);
FORCEPROP 1 LAST OFFPAGE TRUE
J 0
(3050 4000);
PAINT GREEN (3050 4000);
DISPLAY INVISIBLE (3050 4000);
FORCEPROP 1 LAST COMMENT_BODY TRUE
J 0
(2680 4030);
DISPLAY 2.787234 (2680 4030);
PAINT PEACH (2680 4030);
DISPLAY INVISIBLE (2680 4030);
FORCEADD OFFPAGE..2
(2875 4475);
FORCEPROP 2 LAST $XR0 213 
J 0
(3064 4475);
DISPLAY 0.638298 (3064 4475);
PAINT MONO (3064 4475);
FORCEPROP 2 LAST CDS_LIB mstr_standard
J 0
(2875 4475);
DISPLAY 1.617021 (2875 4475);
PAINT ORANGE (2875 4475);
DISPLAY INVISIBLE (2875 4475);
FORCEPROP 2 LAST BOM_COST PROC_VRD_PVCCIO_CPU1
J 0
(3075 4525);
DISPLAY 2.340426 (3075 4525);
PAINT WHITE (3075 4525);
DISPLAY INVISIBLE (3075 4525);
FORCEPROP 2 LAST ROOM PVCCIO_CPU1
J 0
(2475 4550);
DISPLAY 3.127660 (2475 4550);
PAINT WHITE (2475 4550);
DISPLAY INVISIBLE (2475 4550);
FORCEPROP 2 LAST PATH I59
J 0
(3050 4550);
DISPLAY 1.021277 (3050 4550);
PAINT ORANGE (3050 4550);
DISPLAY INVISIBLE (3050 4550);
FORCEPROP 1 LAST OFFPAGE TRUE
J 0
(3200 4350);
PAINT GREEN (3200 4350);
DISPLAY INVISIBLE (3200 4350);
FORCEPROP 1 LAST COMMENT_BODY TRUE
J 0
(2830 4380);
DISPLAY 2.787234 (2830 4380);
PAINT PEACH (2830 4380);
DISPLAY INVISIBLE (2830 4380);
FORCEADD GND..1
(2100 1975);
FORCEPROP 3 LASTPIN (2100 2025) SIG_NAME GND\g
J 0
(2110 2035);
DISPLAY 0.659574 (2110 2035);
PAINT MONO (2110 2035);
DISPLAY INVISIBLE (2110 2035);
FORCEPROP 2 LAST CDS_LIB mstr_symbols
J 0
(2100 1975);
DISPLAY 0.723404 (2100 1975);
PAINT ORANGE (2100 1975);
DISPLAY INVISIBLE (2100 1975);
FORCEPROP 1 LAST PATH I6
J 0
(2175 1975);
DISPLAY 0.872340 (2175 1975);
PAINT AQUA (2175 1975);
DISPLAY INVISIBLE (2175 1975);
FORCEPROP 1 LAST VOLTAGE 0
J 0
(2100 1975);
DISPLAY 0.723404 (2100 1975);
PAINT SKYBLUE (2100 1975);
DISPLAY INVISIBLE (2100 1975);
FORCEPROP 1 LAST SIZE 1B
J 0
(2175 1925);
DISPLAY 0.638298 (2175 1925);
PAINT GREEN (2175 1925);
DISPLAY INVISIBLE (2175 1925);
FORCEPROP 2 LAST ROOM PVCCIO_CPU1
J 0
(1800 2050);
DISPLAY 0.723404 (1800 2050);
PAINT ORANGE (1800 2050);
DISPLAY INVISIBLE (1800 2050);
FORCEPROP 2 LAST BOM_COST PROC_VRD_PVCCIO_CPU1
J 0
(1600 2050);
DISPLAY 0.723404 (1600 2050);
PAINT ORANGE (1600 2050);
DISPLAY INVISIBLE (1600 2050);
FORCEPROP 1 LAST BODY_TYPE PLUMBING
J 0
(2055 1932);
DISPLAY 0.340426 (2055 1932);
PAINT GREEN (2055 1932);
DISPLAY INVISIBLE (2055 1932);
FORCEPROP 1 LAST HDL_POWER GND
J 0
(2100 2125);
DISPLAY 0.638298 (2100 2125);
PAINT GREEN (2100 2125);
DISPLAY INVISIBLE (2100 2125);
FORCEADD OFFPAGE..2
(2850 4825);
FORCEPROP 2 LAST $XR0 213 
J 0
(3039 4825);
DISPLAY 0.638298 (3039 4825);
PAINT MONO (3039 4825);
FORCEPROP 2 LAST ROOM PVCCIO_CPU1
J 0
(2450 4900);
DISPLAY 3.127660 (2450 4900);
PAINT WHITE (2450 4900);
DISPLAY INVISIBLE (2450 4900);
FORCEPROP 2 LAST CDS_LIB mstr_standard
J 0
(2850 4825);
DISPLAY 1.617021 (2850 4825);
PAINT ORANGE (2850 4825);
DISPLAY INVISIBLE (2850 4825);
FORCEPROP 2 LAST PATH I60
J 0
(3025 4900);
DISPLAY 1.021277 (3025 4900);
PAINT ORANGE (3025 4900);
DISPLAY INVISIBLE (3025 4900);
FORCEPROP 2 LAST BOM_COST PROC_VRD_PVCCIO_CPU1
J 0
(3050 4875);
DISPLAY 2.340426 (3050 4875);
PAINT WHITE (3050 4875);
DISPLAY INVISIBLE (3050 4875);
FORCEPROP 1 LAST OFFPAGE TRUE
J 0
(3175 4700);
PAINT GREEN (3175 4700);
DISPLAY INVISIBLE (3175 4700);
FORCEPROP 1 LAST COMMENT_BODY TRUE
J 0
(2805 4730);
DISPLAY 2.787234 (2805 4730);
PAINT PEACH (2805 4730);
DISPLAY INVISIBLE (2805 4730);
FORCEADD PVCCIO_CPU1..1
(3975 3725);
FORCEPROP 3 LASTPIN (3975 3675) SIG_NAME PVCCIO_CPU1\g
J 0
(3985 3685);
DISPLAY 0.659574 (3985 3685);
PAINT MONO (3985 3685);
DISPLAY INVISIBLE (3985 3685);
FORCEPROP 1 LAST VOLTAGE 1.1V
J 0
(3930 3682);
DISPLAY 0.340426 (3930 3682);
PAINT SKYBLUE (3930 3682);
DISPLAY INVISIBLE (3930 3682);
FORCEPROP 2 LAST CDS_LIB mstr_symbols
J 0
(3975 3725);
PAINT ORANGE (3975 3725);
DISPLAY INVISIBLE (3975 3725);
FORCEPROP 1 LAST PATH I64
J 0
(4025 3750);
DISPLAY 0.872340 (4025 3750);
PAINT AQUA (4025 3750);
DISPLAY INVISIBLE (4025 3750);
FORCEPROP 2 LAST ROOM PVCCIO_CPU1
J 0
(3975 3825);
DISPLAY 3.127660 (3975 3825);
PAINT WHITE (3975 3825);
DISPLAY INVISIBLE (3975 3825);
FORCEPROP 2 LAST BOM_COST PROC_VRD_PVCCIO_CPU1
J 0
(3975 3825);
DISPLAY 2.340426 (3975 3825);
PAINT WHITE (3975 3825);
DISPLAY INVISIBLE (3975 3825);
FORCEPROP 1 LAST BODY_TYPE PLUMBING
J 0
(3930 3682);
DISPLAY 0.340426 (3930 3682);
PAINT GREEN (3930 3682);
DISPLAY INVISIBLE (3930 3682);
FORCEPROP 1 LAST HDL_POWER PVCCIO_CPU1
J 1
(3975 3775);
DISPLAY 0.872340 (3975 3775);
PAINT GREEN (3975 3775);
DISPLAY INVISIBLE (3975 3775);
FORCEADD CAP_A..1
(3350 3425);
FORCEPROP 0 LAST GROUP PWR_MLCC_CAP
J 0
(3406 3237);
DISPLAY 0.638298 (3406 3237);
PAINT BROWN (3406 3237);
DISPLAY BOTH (3406 3237);
FORCEPROP 1 LAST PART_NUMBER E15431-004
J 0
(3400 3325);
DISPLAY 0.617021 (3400 3325);
PAINT BLUE (3400 3325);
FORCEPROP 1 LAST PACK_TYPE 0603V
J 0
(3400 3275);
DISPLAY 0.617021 (3400 3275);
PAINT SKYBLUE (3400 3275);
FORCEPROP 1 LAST MATERIAL X6S
J 0
(3400 3375);
DISPLAY 0.617021 (3400 3375);
PAINT SKYBLUE (3400 3375);
FORCEPROP 1 LAST TOLERANCE 20%
J 0
(3400 3425);
DISPLAY 0.617021 (3400 3425);
PAINT SKYBLUE (3400 3425);
FORCEPROP 1 LAST VOLTAGE 4V
J 0
(3400 3475);
DISPLAY 0.617021 (3400 3475);
PAINT SKYBLUE (3400 3475);
FORCEPROP 1 LAST VALUE 22.0UF
J 0
(3400 3525);
DISPLAY 0.617021 (3400 3525);
PAINT SKYBLUE (3400 3525);
FORCEPROP 1 LAST LOCATION C7R1
J 0
(3400 3575);
DISPLAY 0.617021 (3400 3575);
PAINT AQUA (3400 3575);
FORCEPROP 1 LASTPIN (3350 3325) $PN 2
J 0
(3360 3305);
DISPLAY 0.617021 (3360 3305);
PAINT WHITE (3360 3305);
FORCEPROP 1 LASTPIN (3350 3525) $PN 1
J 0
(3360 3505);
DISPLAY 0.617021 (3360 3505);
PAINT WHITE (3360 3505);
FORCEPROP 2 LAST CDS_LIB dev_discrete
J 0
(3350 3425);
PAINT ORANGE (3350 3425);
DISPLAY INVISIBLE (3350 3425);
FORCEPROP 2 LAST CDS_LOCATION C7R1
J 0
(3400 3525);
DISPLAY 0.617021 (3400 3525);
PAINT AQUA (3400 3525);
DISPLAY INVISIBLE (3400 3525);
FORCEPROP 2 LAST CDS_SEC 1
J 0
(3400 3575);
PAINT ORANGE (3400 3575);
DISPLAY INVISIBLE (3400 3575);
FORCEPROP 1 LAST PATH I65
J 0
(3400 3575);
DISPLAY 0.978723 (3400 3575);
PAINT WHITE (3400 3575);
DISPLAY INVISIBLE (3400 3575);
FORCEPROP 2 LAST BOM_COST PROC_VRD_PVCCIO_CPU1
J 0
(3400 3575);
DISPLAY 2.340426 (3400 3575);
PAINT WHITE (3400 3575);
DISPLAY INVISIBLE (3400 3575);
FORCEPROP 2 LAST SEC_TYPE 0603V
J 0
(3405 3625);
DISPLAY 1.659574 (3405 3625);
PAINT ORANGE (3405 3625);
DISPLAY INVISIBLE (3405 3625);
FORCEPROP 2 LAST SEC 1
J 0
(3405 3625);
DISPLAY 1.106383 (3405 3625);
PAINT MONO (3405 3625);
DISPLAY INVISIBLE (3405 3625);
FORCEPROP 2 LAST ROOM PVCCIO_CPU1
J 0
(3400 3575);
DISPLAY 2.340426 (3400 3575);
PAINT WHITE (3400 3575);
DISPLAY INVISIBLE (3400 3575);
FORCEADD GND..1
(3975 3150);
FORCEPROP 3 LASTPIN (3975 3200) SIG_NAME GND\g
J 0
(3985 3210);
DISPLAY 0.659574 (3985 3210);
PAINT MONO (3985 3210);
DISPLAY INVISIBLE (3985 3210);
FORCEPROP 2 LAST ROOM PVCCIO_CPU1
J 0
(3425 3225);
DISPLAY 3.127660 (3425 3225);
PAINT WHITE (3425 3225);
DISPLAY INVISIBLE (3425 3225);
FORCEPROP 2 LAST BOM_COST PROC_VRD_PVCCIO_CPU1
J 0
(3600 3225);
DISPLAY 2.340426 (3600 3225);
PAINT WHITE (3600 3225);
DISPLAY INVISIBLE (3600 3225);
FORCEPROP 1 LAST VOLTAGE 0.0V
J 0
(3930 3107);
DISPLAY 0.340426 (3930 3107);
PAINT SKYBLUE (3930 3107);
DISPLAY INVISIBLE (3930 3107);
FORCEPROP 1 LAST SIZE 1B
J 0
(4050 3100);
DISPLAY 2.787234 (4050 3100);
PAINT GREEN (4050 3100);
DISPLAY INVISIBLE (4050 3100);
FORCEPROP 2 LAST CDS_LIB mstr_symbols
J 0
(3975 3150);
DISPLAY 1.617021 (3975 3150);
PAINT ORANGE (3975 3150);
DISPLAY INVISIBLE (3975 3150);
FORCEPROP 1 LAST PATH I66
J 0
(4050 3150);
DISPLAY 0.872340 (4050 3150);
PAINT AQUA (4050 3150);
DISPLAY INVISIBLE (4050 3150);
FORCEPROP 1 LAST BODY_TYPE PLUMBING
J 0
(3930 3107);
DISPLAY 0.340426 (3930 3107);
PAINT GREEN (3930 3107);
DISPLAY INVISIBLE (3930 3107);
FORCEPROP 1 LAST HDL_POWER GND
J 0
(3975 3300);
DISPLAY 2.787234 (3975 3300);
PAINT GREEN (3975 3300);
DISPLAY INVISIBLE (3975 3300);
FORCEADD GND..1
(1725 3250);
FORCEPROP 3 LASTPIN (1725 3300) SIG_NAME GND\g
J 0
(1735 3310);
DISPLAY 0.659574 (1735 3310);
PAINT MONO (1735 3310);
DISPLAY INVISIBLE (1735 3310);
FORCEPROP 2 LAST ROOM PVCCIO_CPU1
J 0
(1175 3325);
DISPLAY 3.127660 (1175 3325);
PAINT WHITE (1175 3325);
DISPLAY INVISIBLE (1175 3325);
FORCEPROP 2 LAST BOM_COST PROC_VRD_PVCCIO_CPU1
J 0
(1350 3325);
DISPLAY 2.340426 (1350 3325);
PAINT WHITE (1350 3325);
DISPLAY INVISIBLE (1350 3325);
FORCEPROP 1 LAST VOLTAGE 0.0V
J 0
(1680 3207);
DISPLAY 0.340426 (1680 3207);
PAINT SKYBLUE (1680 3207);
DISPLAY INVISIBLE (1680 3207);
FORCEPROP 2 LAST CDS_LIB mstr_symbols
J 0
(1725 3250);
DISPLAY 1.617021 (1725 3250);
PAINT ORANGE (1725 3250);
DISPLAY INVISIBLE (1725 3250);
FORCEPROP 1 LAST SIZE 1B
J 0
(1800 3200);
DISPLAY 2.787234 (1800 3200);
PAINT GREEN (1800 3200);
DISPLAY INVISIBLE (1800 3200);
FORCEPROP 1 LAST PATH I68
J 0
(1800 3250);
DISPLAY 0.872340 (1800 3250);
PAINT AQUA (1800 3250);
DISPLAY INVISIBLE (1800 3250);
FORCEPROP 1 LAST BODY_TYPE PLUMBING
J 0
(1680 3207);
DISPLAY 0.340426 (1680 3207);
PAINT GREEN (1680 3207);
DISPLAY INVISIBLE (1680 3207);
FORCEPROP 1 LAST HDL_POWER GND
J 0
(1725 3400);
DISPLAY 2.787234 (1725 3400);
PAINT GREEN (1725 3400);
DISPLAY INVISIBLE (1725 3400);
FORCEADD CAP..1
(-950 4200);
FORCEPROP 1 LASTPIN (-950 4300) $PN 1
J 0
(-940 4280);
DISPLAY 0.617021 (-940 4280);
PAINT WHITE (-940 4280);
FORCEPROP 1 LAST VALUE 0.22UF
J 0
(-900 4250);
DISPLAY 0.617021 (-900 4250);
PAINT SKYBLUE (-900 4250);
FORCEPROP 1 LAST VOLTAGE 16V
J 0
(-900 4200);
DISPLAY 0.617021 (-900 4200);
PAINT SKYBLUE (-900 4200);
FORCEPROP 1 LAST TOLERANCE 10%
J 0
(-900 4150);
DISPLAY 0.617021 (-900 4150);
PAINT SKYBLUE (-900 4150);
FORCEPROP 1 LAST PACK_TYPE 0402
J 0
(-900 4000);
DISPLAY 0.617021 (-900 4000);
PAINT SKYBLUE (-900 4000);
FORCEPROP 1 LAST PART_NUMBER A36096-155
J 0
(-900 4050);
DISPLAY 0.617021 (-900 4050);
PAINT BLUE (-900 4050);
FORCEPROP 1 LAST MATERIAL X7R
J 0
(-900 4100);
DISPLAY 0.617021 (-900 4100);
PAINT SKYBLUE (-900 4100);
FORCEPROP 1 LASTPIN (-950 4100) $PN 2
J 0
(-940 4080);
DISPLAY 0.617021 (-940 4080);
PAINT WHITE (-940 4080);
FORCEPROP 1 LAST LOCATION C4E23
J 0
(-900 4300);
DISPLAY 0.617021 (-900 4300);
PAINT AQUA (-900 4300);
FORCEPROP 2 LAST CDS_LIB mstr_discrete
J 0
(-950 4200);
DISPLAY 1.617021 (-950 4200);
PAINT ORANGE (-950 4200);
DISPLAY INVISIBLE (-950 4200);
FORCEPROP 2 LAST CDS_LOCATION C4E23
J 0
(-900 4300);
DISPLAY 0.617021 (-900 4300);
PAINT AQUA (-900 4300);
DISPLAY INVISIBLE (-900 4300);
FORCEPROP 2 LAST SEC 1
J 0
(-900 4400);
DISPLAY 1.106383 (-900 4400);
PAINT MONO (-900 4400);
DISPLAY INVISIBLE (-900 4400);
FORCEPROP 2 LAST SEC_TYPE 0402
J 0
(-900 4400);
DISPLAY 1.659574 (-900 4400);
PAINT ORANGE (-900 4400);
DISPLAY INVISIBLE (-900 4400);
FORCEPROP 1 LAST PATH I73
J 0
(-900 4350);
DISPLAY 0.978723 (-900 4350);
PAINT WHITE (-900 4350);
DISPLAY INVISIBLE (-900 4350);
FORCEPROP 2 LAST ROOM PVCCIO_CPU1
J 0
(-900 4350);
DISPLAY 2.212766 (-900 4350);
PAINT WHITE (-900 4350);
DISPLAY INVISIBLE (-900 4350);
FORCEADD CAP..1
(-1700 4150);
FORCEPROP 1 LAST PACK_TYPE 0402
J 0
(-1650 3950);
DISPLAY 0.617021 (-1650 3950);
PAINT SKYBLUE (-1650 3950);
FORCEPROP 1 LAST PART_NUMBER D97712-011
J 0
(-1650 4000);
DISPLAY 0.617021 (-1650 4000);
PAINT BLUE (-1650 4000);
FORCEPROP 1 LAST TOLERANCE 10%
J 0
(-1650 4100);
DISPLAY 0.617021 (-1650 4100);
PAINT SKYBLUE (-1650 4100);
FORCEPROP 1 LAST MATERIAL X6S
J 0
(-1650 4050);
DISPLAY 0.617021 (-1650 4050);
PAINT SKYBLUE (-1650 4050);
FORCEPROP 1 LASTPIN (-1700 4050) $PN 2
J 0
(-1690 4030);
DISPLAY 0.617021 (-1690 4030);
PAINT WHITE (-1690 4030);
FORCEPROP 1 LASTPIN (-1700 4250) $PN 1
J 0
(-1690 4230);
DISPLAY 0.617021 (-1690 4230);
PAINT WHITE (-1690 4230);
FORCEPROP 1 LAST VOLTAGE 16V
J 0
(-1650 4150);
DISPLAY 0.617021 (-1650 4150);
PAINT SKYBLUE (-1650 4150);
FORCEPROP 1 LAST VALUE 1.0UF
J 0
(-1650 4200);
DISPLAY 0.617021 (-1650 4200);
PAINT SKYBLUE (-1650 4200);
FORCEPROP 1 LAST LOCATION C4E22
J 0
(-1650 4250);
DISPLAY 0.617021 (-1650 4250);
PAINT AQUA (-1650 4250);
FORCEPROP 2 LAST CDS_LOCATION C4E22
J 0
(-1650 4250);
DISPLAY 0.617021 (-1650 4250);
PAINT AQUA (-1650 4250);
DISPLAY INVISIBLE (-1650 4250);
FORCEPROP 2 LAST CDS_LIB mstr_discrete
J 0
(-1700 4150);
DISPLAY 1.617021 (-1700 4150);
PAINT ORANGE (-1700 4150);
DISPLAY INVISIBLE (-1700 4150);
FORCEPROP 2 LAST ROOM PVCCIO_CPU1
J 0
(-1650 4300);
DISPLAY 2.212766 (-1650 4300);
PAINT WHITE (-1650 4300);
DISPLAY INVISIBLE (-1650 4300);
FORCEPROP 1 LAST PATH I76
J 0
(-1650 4300);
DISPLAY 0.978723 (-1650 4300);
PAINT WHITE (-1650 4300);
DISPLAY INVISIBLE (-1650 4300);
FORCEPROP 2 LAST SEC 1
J 0
(-1650 4350);
DISPLAY 1.106383 (-1650 4350);
PAINT MONO (-1650 4350);
DISPLAY INVISIBLE (-1650 4350);
FORCEPROP 2 LAST SEC_TYPE 0402
J 0
(-1650 4350);
DISPLAY 1.659574 (-1650 4350);
PAINT ORANGE (-1650 4350);
DISPLAY INVISIBLE (-1650 4350);
FORCEADD CAP_A..1
(-1975 4150);
FORCEPROP 1 LASTPIN (-1975 4250) $PN 1
J 0
(-1965 4230);
DISPLAY 0.617021 (-1965 4230);
PAINT WHITE (-1965 4230);
FORCEPROP 1 LASTPIN (-1975 4050) $PN 2
J 0
(-1965 4030);
DISPLAY 0.617021 (-1965 4030);
PAINT WHITE (-1965 4030);
FORCEPROP 1 LAST TOLERANCE 10%
J 0
(-1925 4100);
DISPLAY 0.617021 (-1925 4100);
PAINT SKYBLUE (-1925 4100);
FORCEPROP 1 LAST MATERIAL X7R
J 0
(-1925 4050);
DISPLAY 0.617021 (-1925 4050);
PAINT SKYBLUE (-1925 4050);
FORCEPROP 1 LAST PART_NUMBER A36096-030
J 0
(-1925 4000);
DISPLAY 0.617021 (-1925 4000);
PAINT BLUE (-1925 4000);
FORCEPROP 1 LAST PACK_TYPE 0402V
J 0
(-1925 3950);
DISPLAY 0.617021 (-1925 3950);
PAINT SKYBLUE (-1925 3950);
FORCEPROP 1 LAST VOLTAGE 16V
J 0
(-1925 4150);
DISPLAY 0.617021 (-1925 4150);
PAINT SKYBLUE (-1925 4150);
FORCEPROP 1 LAST VALUE 0.1UF
J 0
(-1925 4200);
DISPLAY 0.617021 (-1925 4200);
PAINT SKYBLUE (-1925 4200);
FORCEPROP 1 LAST LOCATION C4E13
J 0
(-1925 4250);
DISPLAY 0.617021 (-1925 4250);
PAINT AQUA (-1925 4250);
FORCEPROP 2 LAST ROOM PVCCIO_CPU1
J 0
(-1925 4300);
DISPLAY 2.212766 (-1925 4300);
PAINT WHITE (-1925 4300);
DISPLAY INVISIBLE (-1925 4300);
FORCEPROP 2 LAST SEC 1
J 0
(-1925 4350);
DISPLAY 1.106383 (-1925 4350);
PAINT MONO (-1925 4350);
DISPLAY INVISIBLE (-1925 4350);
FORCEPROP 2 LAST SEC_TYPE 0402V
J 0
(-1925 4350);
DISPLAY 1.659574 (-1925 4350);
PAINT ORANGE (-1925 4350);
DISPLAY INVISIBLE (-1925 4350);
FORCEPROP 2 LAST CDS_SEC 1
J 0
(-1925 4300);
PAINT ORANGE (-1925 4300);
DISPLAY INVISIBLE (-1925 4300);
FORCEPROP 1 LAST PATH I77
J 0
(-1925 4300);
DISPLAY 0.978723 (-1925 4300);
PAINT WHITE (-1925 4300);
DISPLAY INVISIBLE (-1925 4300);
FORCEPROP 2 LAST CDS_LOCATION C4E13
J 0
(-1925 4250);
DISPLAY 0.617021 (-1925 4250);
PAINT AQUA (-1925 4250);
DISPLAY INVISIBLE (-1925 4250);
FORCEPROP 2 LAST CDS_LIB dev_discrete
J 0
(-1975 4150);
PAINT ORANGE (-1975 4150);
DISPLAY INVISIBLE (-1975 4150);
FORCEADD CAP..1
R 2
(-1625 3575);
FORCEPROP 1 LAST PACK_TYPE 0402
J 2
(-1675 3375);
DISPLAY 0.617021 (-1675 3375);
PAINT SKYBLUE (-1675 3375);
FORCEPROP 1 LAST PART_NUMBER A36096-104
J 2
(-1675 3425);
DISPLAY 0.617021 (-1675 3425);
PAINT BLUE (-1675 3425);
FORCEPROP 1 LAST MATERIAL X7R
J 2
(-1675 3475);
DISPLAY 0.617021 (-1675 3475);
PAINT SKYBLUE (-1675 3475);
FORCEPROP 1 LAST TOLERANCE 10%
J 2
(-1675 3525);
DISPLAY 0.617021 (-1675 3525);
PAINT SKYBLUE (-1675 3525);
FORCEPROP 1 LAST VOLTAGE 16V
J 2
(-1675 3575);
DISPLAY 0.617021 (-1675 3575);
PAINT SKYBLUE (-1675 3575);
FORCEPROP 1 LAST VALUE 0.220UF
J 2
(-1675 3625);
DISPLAY 0.617021 (-1675 3625);
PAINT SKYBLUE (-1675 3625);
FORCEPROP 1 LAST LOCATION C4E18
J 2
(-1675 3675);
DISPLAY 0.617021 (-1675 3675);
PAINT AQUA (-1675 3675);
FORCEPROP 1 LASTPIN (-1625 3675) $PN 1
J 2
(-1635 3655);
DISPLAY 0.617021 (-1635 3655);
PAINT ORANGE (-1635 3655);
FORCEPROP 1 LASTPIN (-1625 3475) $PN 2
J 2
(-1635 3455);
DISPLAY 0.617021 (-1635 3455);
PAINT ORANGE (-1635 3455);
FORCEPROP 2 LAST CDS_LOCATION C4E18
J 2
(-1675 3675);
DISPLAY 0.617021 (-1675 3675);
PAINT AQUA (-1675 3675);
DISPLAY INVISIBLE (-1675 3675);
FORCEPROP 2 LAST CDS_LIB mstr_discrete
J 0
(-1625 3575);
PAINT ORANGE (-1625 3575);
DISPLAY INVISIBLE (-1625 3575);
FORCEPROP 1 LAST PATH I78
J 2
(-1675 3725);
DISPLAY 0.978723 (-1675 3725);
PAINT WHITE (-1675 3725);
DISPLAY INVISIBLE (-1675 3725);
FORCEPROP 2 LAST SEC_TYPE 0402
J 0
(-1675 3775);
DISPLAY 1.021277 (-1675 3775);
PAINT ORANGE (-1675 3775);
DISPLAY INVISIBLE (-1675 3775);
FORCEPROP 2 LAST SEC 1
J 0
(-1675 3775);
DISPLAY 0.680851 (-1675 3775);
PAINT MONO (-1675 3775);
DISPLAY INVISIBLE (-1675 3775);
FORCEPROP 0 LAST SPOF TRUE
J 0
(-1675 3775);
DISPLAY 1.021277 (-1675 3775);
PAINT ORANGE (-1675 3775);
DISPLAY INVISIBLE (-1675 3775);
FORCEPROP 2 LAST ROOM PVCCIO_CPU1
J 0
(-1675 3725);
DISPLAY 2.212766 (-1675 3725);
PAINT WHITE (-1675 3725);
DISPLAY INVISIBLE (-1675 3725);
FORCEADD CAP..1
(-2250 4150);
FORCEPROP 1 LASTPIN (-2250 4250) $PN 1
J 0
(-2240 4230);
DISPLAY 0.617021 (-2240 4230);
PAINT WHITE (-2240 4230);
FORCEPROP 1 LAST VOLTAGE 16V
J 0
(-2200 4150);
DISPLAY 0.617021 (-2200 4150);
PAINT SKYBLUE (-2200 4150);
FORCEPROP 1 LAST VALUE 1.0UF
J 0
(-2200 4200);
DISPLAY 0.617021 (-2200 4200);
PAINT SKYBLUE (-2200 4200);
FORCEPROP 1 LAST LOCATION C4E15
J 0
(-2200 4250);
DISPLAY 0.617021 (-2200 4250);
PAINT AQUA (-2200 4250);
FORCEPROP 1 LAST PACK_TYPE 0402
J 0
(-2200 3950);
DISPLAY 0.617021 (-2200 3950);
PAINT SKYBLUE (-2200 3950);
FORCEPROP 1 LAST PART_NUMBER D97712-011
J 0
(-2200 4000);
DISPLAY 0.617021 (-2200 4000);
PAINT BLUE (-2200 4000);
FORCEPROP 1 LAST MATERIAL X6S
J 0
(-2200 4050);
DISPLAY 0.617021 (-2200 4050);
PAINT SKYBLUE (-2200 4050);
FORCEPROP 1 LASTPIN (-2250 4050) $PN 2
J 0
(-2240 4030);
DISPLAY 0.617021 (-2240 4030);
PAINT WHITE (-2240 4030);
FORCEPROP 1 LAST TOLERANCE 10%
J 0
(-2200 4100);
DISPLAY 0.617021 (-2200 4100);
PAINT SKYBLUE (-2200 4100);
FORCEPROP 2 LAST CDS_LIB mstr_discrete
J 0
(-2250 4150);
DISPLAY 1.617021 (-2250 4150);
PAINT ORANGE (-2250 4150);
DISPLAY INVISIBLE (-2250 4150);
FORCEPROP 2 LAST CDS_LOCATION C4E15
J 0
(-2200 4250);
DISPLAY 0.617021 (-2200 4250);
PAINT AQUA (-2200 4250);
DISPLAY INVISIBLE (-2200 4250);
FORCEPROP 1 LAST PATH I79
J 0
(-2200 4300);
DISPLAY 0.978723 (-2200 4300);
PAINT WHITE (-2200 4300);
DISPLAY INVISIBLE (-2200 4300);
FORCEPROP 2 LAST SEC 1
J 0
(-2200 4350);
DISPLAY 1.106383 (-2200 4350);
PAINT MONO (-2200 4350);
DISPLAY INVISIBLE (-2200 4350);
FORCEPROP 2 LAST SEC_TYPE 0402
J 0
(-2200 4350);
DISPLAY 1.659574 (-2200 4350);
PAINT ORANGE (-2200 4350);
DISPLAY INVISIBLE (-2200 4350);
FORCEPROP 2 LAST ROOM PVCCIO_CPU1
J 0
(-2200 4300);
DISPLAY 2.212766 (-2200 4300);
PAINT WHITE (-2200 4300);
DISPLAY INVISIBLE (-2200 4300);
FORCEADD CAP..1
(-2525 4150);
FORCEPROP 1 LAST PACK_TYPE 0805
J 0
(-2475 3950);
DISPLAY 0.617021 (-2475 3950);
PAINT SKYBLUE (-2475 3950);
FORCEPROP 1 LASTPIN (-2525 4050) $PN 2
J 0
(-2515 4030);
DISPLAY 0.617021 (-2515 4030);
PAINT WHITE (-2515 4030);
FORCEPROP 1 LASTPIN (-2525 4250) $PN 1
J 0
(-2515 4230);
DISPLAY 0.617021 (-2515 4230);
PAINT WHITE (-2515 4230);
FORCEPROP 1 LAST MATERIAL X6S
J 0
(-2475 4050);
DISPLAY 0.617021 (-2475 4050);
PAINT SKYBLUE (-2475 4050);
FORCEPROP 1 LAST VOLTAGE 16V
J 0
(-2475 4150);
DISPLAY 0.617021 (-2475 4150);
PAINT SKYBLUE (-2475 4150);
FORCEPROP 1 LAST TOLERANCE 10%
J 0
(-2475 4100);
DISPLAY 0.617021 (-2475 4100);
PAINT SKYBLUE (-2475 4100);
FORCEPROP 1 LAST VALUE 10UF
J 0
(-2475 4200);
DISPLAY 0.617021 (-2475 4200);
PAINT SKYBLUE (-2475 4200);
FORCEPROP 1 LAST LOCATION C6R14
J 0
(-2475 4250);
DISPLAY 0.617021 (-2475 4250);
PAINT AQUA (-2475 4250);
FORCEPROP 1 LAST PART_NUMBER C95333-007
J 0
(-2475 4000);
DISPLAY 0.617021 (-2475 4000);
PAINT BLUE (-2475 4000);
FORCEPROP 2 LAST CDS_LIB mstr_discrete
J 0
(-2525 4150);
DISPLAY 1.617021 (-2525 4150);
PAINT ORANGE (-2525 4150);
DISPLAY INVISIBLE (-2525 4150);
FORCEPROP 2 LAST CDS_LOCATION C6R14
J 0
(-2475 4250);
DISPLAY 0.617021 (-2475 4250);
PAINT AQUA (-2475 4250);
DISPLAY INVISIBLE (-2475 4250);
FORCEPROP 2 LAST SEC 1
J 0
(-2475 4350);
DISPLAY 1.106383 (-2475 4350);
PAINT MONO (-2475 4350);
DISPLAY INVISIBLE (-2475 4350);
FORCEPROP 2 LAST SEC_TYPE 0805
J 0
(-2475 4350);
DISPLAY 1.659574 (-2475 4350);
PAINT ORANGE (-2475 4350);
DISPLAY INVISIBLE (-2475 4350);
FORCEPROP 1 LAST PATH I80
J 0
(-2475 4300);
DISPLAY 0.978723 (-2475 4300);
PAINT WHITE (-2475 4300);
DISPLAY INVISIBLE (-2475 4300);
FORCEPROP 2 LAST ROOM PVCCIO_CPU1
J 0
(-2475 4300);
DISPLAY 2.212766 (-2475 4300);
PAINT WHITE (-2475 4300);
DISPLAY INVISIBLE (-2475 4300);
FORCEADD CAP..1
(-2800 4150);
FORCEPROP 1 LAST TOLERANCE 10%
J 0
(-2750 4100);
DISPLAY 0.617021 (-2750 4100);
PAINT SKYBLUE (-2750 4100);
FORCEPROP 1 LAST VOLTAGE 16V
J 0
(-2750 4150);
DISPLAY 0.617021 (-2750 4150);
PAINT SKYBLUE (-2750 4150);
FORCEPROP 1 LAST VALUE 10UF
J 0
(-2750 4200);
DISPLAY 0.617021 (-2750 4200);
PAINT SKYBLUE (-2750 4200);
FORCEPROP 1 LASTPIN (-2800 4250) $PN 1
J 0
(-2790 4230);
DISPLAY 0.617021 (-2790 4230);
PAINT WHITE (-2790 4230);
FORCEPROP 1 LASTPIN (-2800 4050) $PN 2
J 0
(-2790 4030);
DISPLAY 0.617021 (-2790 4030);
PAINT WHITE (-2790 4030);
FORCEPROP 1 LAST PACK_TYPE 0805
J 0
(-2750 3950);
DISPLAY 0.617021 (-2750 3950);
PAINT SKYBLUE (-2750 3950);
FORCEPROP 1 LAST LOCATION C6R10
J 0
(-2750 4250);
DISPLAY 0.617021 (-2750 4250);
PAINT AQUA (-2750 4250);
FORCEPROP 1 LAST PART_NUMBER C95333-007
J 0
(-2750 4000);
DISPLAY 0.617021 (-2750 4000);
PAINT BLUE (-2750 4000);
FORCEPROP 1 LAST MATERIAL X6S
J 0
(-2750 4050);
DISPLAY 0.617021 (-2750 4050);
PAINT SKYBLUE (-2750 4050);
FORCEPROP 2 LAST SEC_TYPE 0805
J 0
(-2750 4350);
DISPLAY 1.659574 (-2750 4350);
PAINT ORANGE (-2750 4350);
DISPLAY INVISIBLE (-2750 4350);
FORCEPROP 2 LAST SEC 1
J 0
(-2750 4350);
DISPLAY 1.106383 (-2750 4350);
PAINT MONO (-2750 4350);
DISPLAY INVISIBLE (-2750 4350);
FORCEPROP 1 LAST PATH I81
J 0
(-2750 4300);
DISPLAY 0.978723 (-2750 4300);
PAINT WHITE (-2750 4300);
DISPLAY INVISIBLE (-2750 4300);
FORCEPROP 2 LAST ROOM PVCCIO_CPU1
J 0
(-2750 4300);
DISPLAY 2.212766 (-2750 4300);
PAINT WHITE (-2750 4300);
DISPLAY INVISIBLE (-2750 4300);
FORCEPROP 2 LAST CDS_LOCATION C6R10
J 0
(-2750 4250);
DISPLAY 0.617021 (-2750 4250);
PAINT AQUA (-2750 4250);
DISPLAY INVISIBLE (-2750 4250);
FORCEPROP 2 LAST CDS_LIB mstr_discrete
J 0
(-2800 4150);
DISPLAY 1.617021 (-2800 4150);
PAINT ORANGE (-2800 4150);
DISPLAY INVISIBLE (-2800 4150);
FORCEADD OFFPAGE..1
(-2325 3825);
FORCEPROP 2 LAST $XR0 213 
J 0
(-2577 3825);
DISPLAY 0.638298 (-2577 3825);
PAINT MONO (-2577 3825);
FORCEPROP 2 LAST ROOM PVCCIO_CPU1
J 0
(-2725 3900);
DISPLAY 3.127660 (-2725 3900);
PAINT WHITE (-2725 3900);
DISPLAY INVISIBLE (-2725 3900);
FORCEPROP 2 LAST BOM_COST PROC_VRD_PVCCIO_CPU1
J 0
(-2575 3875);
DISPLAY 2.340426 (-2575 3875);
PAINT WHITE (-2575 3875);
DISPLAY INVISIBLE (-2575 3875);
FORCEPROP 2 LAST PATH I82
J 0
(-2275 3900);
DISPLAY 1.021277 (-2275 3900);
PAINT ORANGE (-2275 3900);
DISPLAY INVISIBLE (-2275 3900);
FORCEPROP 2 LAST CDS_LIB mstr_standard
J 0
(-2325 3825);
DISPLAY 1.617021 (-2325 3825);
PAINT ORANGE (-2325 3825);
DISPLAY INVISIBLE (-2325 3825);
FORCEPROP 1 LAST OFFPAGE TRUE
J 0
(-2000 3700);
PAINT GREEN (-2000 3700);
DISPLAY INVISIBLE (-2000 3700);
FORCEPROP 1 LAST COMMENT_BODY TRUE
J 0
(-2200 3725);
DISPLAY 2.723404 (-2200 3725);
PAINT PEACH (-2200 3725);
DISPLAY INVISIBLE (-2200 3725);
FORCEADD CAP..1
(-3100 4150);
FORCEPROP 1 LAST LOCATION C6R8
J 0
(-3050 4250);
DISPLAY 0.617021 (-3050 4250);
PAINT AQUA (-3050 4250);
FORCEPROP 1 LAST VALUE 10UF
J 0
(-3050 4200);
DISPLAY 0.617021 (-3050 4200);
PAINT SKYBLUE (-3050 4200);
FORCEPROP 1 LAST MATERIAL X6S
J 0
(-3050 4050);
DISPLAY 0.617021 (-3050 4050);
PAINT SKYBLUE (-3050 4050);
FORCEPROP 1 LASTPIN (-3100 4250) $PN 1
J 0
(-3090 4230);
DISPLAY 0.617021 (-3090 4230);
PAINT WHITE (-3090 4230);
FORCEPROP 1 LASTPIN (-3100 4050) $PN 2
J 0
(-3090 4030);
DISPLAY 0.617021 (-3090 4030);
PAINT WHITE (-3090 4030);
FORCEPROP 1 LAST PACK_TYPE 0805
J 0
(-3050 3950);
DISPLAY 0.617021 (-3050 3950);
PAINT SKYBLUE (-3050 3950);
FORCEPROP 1 LAST VOLTAGE 16V
J 0
(-3050 4150);
DISPLAY 0.617021 (-3050 4150);
PAINT SKYBLUE (-3050 4150);
FORCEPROP 1 LAST TOLERANCE 10%
J 0
(-3050 4100);
DISPLAY 0.617021 (-3050 4100);
PAINT SKYBLUE (-3050 4100);
FORCEPROP 1 LAST PART_NUMBER C95333-007
J 0
(-3050 4000);
DISPLAY 0.617021 (-3050 4000);
PAINT BLUE (-3050 4000);
FORCEPROP 2 LAST ROOM PVCCIO_CPU1
J 0
(-3050 4300);
DISPLAY 2.212766 (-3050 4300);
PAINT WHITE (-3050 4300);
DISPLAY INVISIBLE (-3050 4300);
FORCEPROP 1 LAST PATH I83
J 0
(-3050 4300);
DISPLAY 0.978723 (-3050 4300);
PAINT WHITE (-3050 4300);
DISPLAY INVISIBLE (-3050 4300);
FORCEPROP 2 LAST SEC 1
J 0
(-3050 4350);
DISPLAY 1.106383 (-3050 4350);
PAINT MONO (-3050 4350);
DISPLAY INVISIBLE (-3050 4350);
FORCEPROP 2 LAST SEC_TYPE 0805
J 0
(-3050 4350);
DISPLAY 1.659574 (-3050 4350);
PAINT ORANGE (-3050 4350);
DISPLAY INVISIBLE (-3050 4350);
FORCEPROP 2 LAST CDS_LOCATION C6R8
J 0
(-3050 4250);
DISPLAY 0.617021 (-3050 4250);
PAINT AQUA (-3050 4250);
DISPLAY INVISIBLE (-3050 4250);
FORCEPROP 2 LAST CDS_LIB mstr_discrete
J 0
(-3100 4150);
DISPLAY 1.617021 (-3100 4150);
PAINT ORANGE (-3100 4150);
DISPLAY INVISIBLE (-3100 4150);
FORCEADD GND..1
(-3100 3825);
FORCEPROP 3 LASTPIN (-3100 3875) SIG_NAME GND\g
J 0
(-3090 3885);
DISPLAY 0.659574 (-3090 3885);
PAINT MONO (-3090 3885);
DISPLAY INVISIBLE (-3090 3885);
FORCEPROP 1 LAST PATH I84
J 0
(-3025 3825);
DISPLAY 0.872340 (-3025 3825);
PAINT AQUA (-3025 3825);
DISPLAY INVISIBLE (-3025 3825);
FORCEPROP 1 LAST VOLTAGE 0.0V
J 0
(-3145 3782);
DISPLAY 0.340426 (-3145 3782);
PAINT SKYBLUE (-3145 3782);
DISPLAY INVISIBLE (-3145 3782);
FORCEPROP 2 LAST CDS_LIB mstr_symbols
J 0
(-3100 3825);
DISPLAY 1.617021 (-3100 3825);
PAINT ORANGE (-3100 3825);
DISPLAY INVISIBLE (-3100 3825);
FORCEPROP 1 LAST SIZE 1B
J 0
(-3025 3775);
DISPLAY 2.787234 (-3025 3775);
PAINT GREEN (-3025 3775);
DISPLAY INVISIBLE (-3025 3775);
FORCEPROP 2 LAST ROOM PVCCIO_CPU1
J 0
(-3650 3900);
DISPLAY 3.127660 (-3650 3900);
PAINT WHITE (-3650 3900);
DISPLAY INVISIBLE (-3650 3900);
FORCEPROP 2 LAST BOM_COST PROC_VRD_PVCCIO_CPU1
J 0
(-3475 3900);
DISPLAY 2.340426 (-3475 3900);
PAINT WHITE (-3475 3900);
DISPLAY INVISIBLE (-3475 3900);
FORCEPROP 1 LAST BODY_TYPE PLUMBING
J 0
(-3145 3782);
DISPLAY 0.340426 (-3145 3782);
PAINT GREEN (-3145 3782);
DISPLAY INVISIBLE (-3145 3782);
FORCEPROP 1 LAST HDL_POWER GND
J 0
(-3100 3975);
DISPLAY 2.787234 (-3100 3975);
PAINT GREEN (-3100 3975);
DISPLAY INVISIBLE (-3100 3975);
FORCEADD P5V_STBY..1
(-675 4850);
FORCEPROP 3 LASTPIN (-675 4800) SIG_NAME P5V_STBY\g
J 0
(-665 4810);
DISPLAY 0.659574 (-665 4810);
PAINT MONO (-665 4810);
DISPLAY INVISIBLE (-665 4810);
FORCEPROP 1 LAST VOLTAGE 5.0V
J 0
(-720 4807);
DISPLAY 0.340426 (-720 4807);
PAINT SKYBLUE (-720 4807);
DISPLAY INVISIBLE (-720 4807);
FORCEPROP 1 LAST PATH I88
J 0
(-630 4852);
DISPLAY 0.340426 (-630 4852);
PAINT GREEN (-630 4852);
DISPLAY INVISIBLE (-630 4852);
FORCEPROP 1 LAST SIZE 1B
J 0
(-630 4872);
DISPLAY 0.340426 (-630 4872);
PAINT GREEN (-630 4872);
DISPLAY INVISIBLE (-630 4872);
FORCEPROP 2 LAST CDS_LIB mstr_symbols
J 0
(-675 4850);
PAINT ORANGE (-675 4850);
DISPLAY INVISIBLE (-675 4850);
FORCEPROP 1 LAST BODY_TYPE PLUMBING
J 0
(-720 4807);
DISPLAY 0.340426 (-720 4807);
PAINT GREEN (-720 4807);
DISPLAY INVISIBLE (-720 4807);
FORCEPROP 1 LAST HDL_POWER P5V_STBY
J 0
(-975 4725);
DISPLAY 0.872340 (-975 4725);
PAINT ORANGE (-975 4725);
DISPLAY INVISIBLE (-975 4725);
FORCEADD UNIVERSAL_POWER..1
(-3100 4550);
FORCEPROP 3 LASTPIN (-3100 4500) SIG_NAME VR_FET_SW_P12V_STBY_PVCCIN_CPU0\g
J 0
(-3090 4510);
DISPLAY 0.659574 (-3090 4510);
PAINT MONO (-3090 4510);
DISPLAY INVISIBLE (-3090 4510);
FORCEPROP 1 LAST HDL_POWER VR_FET_SW_P12V_STBY_PVCCIN_CPU0
J 1
(-3000 4600);
DISPLAY 0.617021 (-3000 4600);
PAINT GREEN (-3000 4600);
FORCEPROP 1 LAST PATH I89
J 0
(-3050 4575);
DISPLAY 0.872340 (-3050 4575);
PAINT AQUA (-3050 4575);
DISPLAY INVISIBLE (-3050 4575);
FORCEPROP 2 LAST CDS_LIB mstr_symbols
J 0
(-3100 4550);
PAINT ORANGE (-3100 4550);
DISPLAY INVISIBLE (-3100 4550);
FORCEADD OFFPAGE..1
(-3050 1300);
FORCEPROP 2 LAST $XR0 73 
J 0
(-3301 1300);
DISPLAY 0.638298 (-3301 1300);
PAINT MONO (-3301 1300);
FORCEPROP 2 LAST CDS_LIB mstr_standard
J 0
(-3050 1300);
PAINT ORANGE (-3050 1300);
DISPLAY INVISIBLE (-3050 1300);
FORCEPROP 2 LAST PATH I95
J 0
(-3300 1350);
DISPLAY 1.021277 (-3300 1350);
PAINT ORANGE (-3300 1350);
DISPLAY INVISIBLE (-3300 1350);
FORCEPROP 2 LAST ROOM VCCIN_CPU0_DECAP_VR
J 0
(-3575 1375);
PAINT ORANGE (-3575 1375);
DISPLAY INVISIBLE (-3575 1375);
FORCEPROP 2 LAST BOM_COST PROC_VRD_VCCIN_CPU0
J 0
(-3250 1350);
PAINT MONO (-3250 1350);
DISPLAY INVISIBLE (-3250 1350);
FORCEPROP 1 LAST OFFPAGE TRUE
J 0
(-2725 1175);
DISPLAY 0.893617 (-2725 1175);
PAINT GREEN (-2725 1175);
DISPLAY INVISIBLE (-2725 1175);
FORCEPROP 1 LAST COMMENT_BODY TRUE
J 0
(-2925 1200);
DISPLAY 0.893617 (-2925 1200);
PAINT GREEN (-2925 1200);
DISPLAY INVISIBLE (-2925 1200);
FORCEADD CAP_A..1
(-1725 1575);
FORCEPROP 1 LAST PART_NUMBER A36096-030
J 0
(-1675 1425);
DISPLAY 0.617021 (-1675 1425);
PAINT BLUE (-1675 1425);
FORCEPROP 1 LAST MATERIAL EMPTY
J 0
(-1675 1475);
DISPLAY 0.617021 (-1675 1475);
PAINT RED (-1675 1475);
FORCEPROP 1 LAST PACK_TYPE 0402V
J 0
(-1675 1375);
DISPLAY 0.617021 (-1675 1375);
PAINT SKYBLUE (-1675 1375);
FORCEPROP 1 LAST LOCATION C3D27
J 0
(-1675 1675);
DISPLAY 0.617021 (-1675 1675);
PAINT AQUA (-1675 1675);
FORCEPROP 1 LAST VALUE 0.1UF
J 0
(-1675 1625);
DISPLAY 0.617021 (-1675 1625);
PAINT SKYBLUE (-1675 1625);
FORCEPROP 1 LAST VOLTAGE 16V
J 0
(-1675 1575);
DISPLAY 0.617021 (-1675 1575);
PAINT SKYBLUE (-1675 1575);
FORCEPROP 1 LASTPIN (-1725 1675) $PN 1
J 0
(-1715 1655);
DISPLAY 0.617021 (-1715 1655);
PAINT ORANGE (-1715 1655);
FORCEPROP 1 LAST TOLERANCE 10%
J 0
(-1675 1525);
DISPLAY 0.617021 (-1675 1525);
PAINT SKYBLUE (-1675 1525);
FORCEPROP 1 LASTPIN (-1725 1475) $PN 2
J 0
(-1715 1455);
DISPLAY 0.617021 (-1715 1455);
PAINT ORANGE (-1715 1455);
FORCEPROP 2 LAST SEC_TYPE 0402V
J 0
(-1675 1775);
DISPLAY 1.021277 (-1675 1775);
PAINT ORANGE (-1675 1775);
DISPLAY INVISIBLE (-1675 1775);
FORCEPROP 2 LAST SEC 1
J 0
(-1675 1775);
DISPLAY 0.680851 (-1675 1775);
PAINT MONO (-1675 1775);
DISPLAY INVISIBLE (-1675 1775);
FORCEPROP 2 LAST ROOM PVCCIO_CPU1
J 0
(-1675 1725);
DISPLAY 0.723404 (-1675 1725);
PAINT ORANGE (-1675 1725);
DISPLAY INVISIBLE (-1675 1725);
FORCEPROP 1 LAST PATH I96
J 0
(-1675 1725);
DISPLAY 0.978723 (-1675 1725);
PAINT WHITE (-1675 1725);
DISPLAY INVISIBLE (-1675 1725);
FORCEPROP 2 LAST CDS_LOCATION C3D27
J 0
(-1675 1675);
DISPLAY 0.617021 (-1675 1675);
PAINT AQUA (-1675 1675);
DISPLAY INVISIBLE (-1675 1675);
FORCEPROP 2 LAST BOM_COST PROC_VRD_VCCIO_CPU1
J 0
(-1675 1725);
DISPLAY 0.723404 (-1675 1725);
PAINT ORANGE (-1675 1725);
DISPLAY INVISIBLE (-1675 1725);
FORCEPROP 2 LAST CDS_LIB dev_discrete
J 0
(-1725 1575);
PAINT ORANGE (-1725 1575);
DISPLAY INVISIBLE (-1725 1575);
FORCEADD OFFPAGE..1
(-3050 1750);
FORCEPROP 2 LAST $XR0 73 
J 0
(-3301 1750);
DISPLAY 0.638298 (-3301 1750);
PAINT MONO (-3301 1750);
FORCEPROP 2 LAST CDS_LIB mstr_standard
J 2
(-3050 1750);
PAINT ORANGE (-3050 1750);
DISPLAY INVISIBLE (-3050 1750);
FORCEPROP 2 LAST BOM_COST PROC_VRD_VCCIN_CPU0
J 0
(-3250 1800);
PAINT MONO (-3250 1800);
DISPLAY INVISIBLE (-3250 1800);
FORCEPROP 2 LAST PATH I97
J 0
(-3300 1800);
DISPLAY 1.021277 (-3300 1800);
PAINT ORANGE (-3300 1800);
DISPLAY INVISIBLE (-3300 1800);
FORCEPROP 2 LAST ROOM VCCIN_CPU0_DECAP_VR
J 0
(-3575 1825);
PAINT ORANGE (-3575 1825);
DISPLAY INVISIBLE (-3575 1825);
FORCEPROP 1 LAST OFFPAGE TRUE
J 0
(-2725 1625);
DISPLAY 0.893617 (-2725 1625);
PAINT GREEN (-2725 1625);
DISPLAY INVISIBLE (-2725 1625);
FORCEPROP 1 LAST COMMENT_BODY TRUE
J 0
(-2925 1650);
DISPLAY 0.893617 (-2925 1650);
PAINT GREEN (-2925 1650);
DISPLAY INVISIBLE (-2925 1650);
FORCEADD INTEL_CORP_BPAGE..1
(4250 200);
FORCEPROP 1 LAST CDS_CON_LAST_MODIFIED Fri Jun 16 17:49:17 2017
J 0
(2825 525);
PAINT ORANGE (2825 525);
DISPLAY INVISIBLE (2825 525);
FORCEPROP 1 LAST CUSTOM_TXT_CDS <CURRENT_DESIGN_SHEET> OF <TOTAL_DESIGN_SHEETS>
J 0
(3750 225);
PAINT ORANGE (3750 225);
FORCEPROP 1 LAST CUSTOM_TXT_CDS <CON_LAST_MODIFIED>
J 0
(250 300);
PAINT ORANGE (250 300);
FORCEPROP 2 LAST CUSTOM_TXT_CDS <XR_PAGE_TITLE>
J 0
(-3640 5450);
DISPLAY 0.638298 (-3640 5450);
PAINT PINK (-3640 5450);
DISPLAY INVISIBLE (-3640 5450);
FORCEPROP 1 LAST SCH_TITLE PVCCIO CPU1 (2 OF 2)
J 0
(-3700 250);
DISPLAY 1.212766 (-3700 250);
PAINT ORANGE (-3700 250);
FORCEPROP 2 LAST CDS_LIB mstr_symbols
J 0
(4250 200);
PAINT MONO (4250 200);
DISPLAY INVISIBLE (4250 200);
FORCEPROP 2 LAST PAGE_BORDER TRUE
J 0
(-3640 5450);
DISPLAY 0.638298 (-3640 5450);
PAINT PINK (-3640 5450);
DISPLAY INVISIBLE (-3640 5450);
FORCEPROP 1 LAST COMMENT_BODY TRUE
J 0
(4262 212);
DISPLAY 0.468085 (4262 212);
PAINT GREEN (4262 212);
DISPLAY INVISIBLE (4262 212);
FORCEPROP 2 LAST CDS_XR_PAGE_TITLE CR-214 : @BASEBOARD_FAB2_LIB.BASEBOARD_FAB2(SCH_1):PAGE214
J 0
(-3640 5450);
DISPLAY 0.638298 (-3640 5450);
PAINT PINK (-3640 5450);
DISPLAY INVISIBLE (-3640 5450);
FORCEADD DNS..3
(-1245 1295);
PAINT RED (-1245 1295);
FORCEPROP 2 LAST CDS_LIB mstr_misc
J 0
(-1245 1295);
PAINT ORANGE (-1245 1295);
DISPLAY INVISIBLE (-1245 1295);
FORCEPROP 1 LAST COMMENT_BODY TRUE
R 1
J 0
(-1170 1070);
DISPLAY 0.872340 (-1170 1070);
PAINT GREEN (-1170 1070);
DISPLAY INVISIBLE (-1170 1070);
FORCEADD DNS..3
(-1245 1745);
PAINT RED (-1245 1745);
FORCEPROP 2 LAST CDS_LIB mstr_misc
J 0
(-1245 1745);
PAINT ORANGE (-1245 1745);
DISPLAY INVISIBLE (-1245 1745);
FORCEPROP 1 LAST COMMENT_BODY TRUE
R 1
J 0
(-1170 1520);
DISPLAY 0.872340 (-1170 1520);
PAINT GREEN (-1170 1520);
DISPLAY INVISIBLE (-1170 1520);
FORCEADD DESIGN_NOTE..1
(-2450 2475);
PAINT PURPLE (-2450 2475);
FORCEPROP 2 LAST BOM_COST SM_CONTROLLER
J 0
(-2650 2425);
PAINT MONO (-2650 2425);
DISPLAY INVISIBLE (-2650 2425);
FORCEPROP 2 LAST CDS_LIB mstr_symbols
J 0
(-2450 2475);
PAINT ORANGE (-2450 2475);
DISPLAY INVISIBLE (-2450 2475);
FORCEPROP 2 LAST ROOM PVCCIN_CPU0_VR
J 0
(-2650 2425);
PAINT MONO (-2650 2425);
DISPLAY INVISIBLE (-2650 2425);
FORCEPROP 1 LAST COMMENT_BODY TRUE
J 0
(-2425 2575);
DISPLAY 1.319149 (-2425 2575);
PAINT GREEN (-2425 2575);
DISPLAY INVISIBLE (-2425 2575);
FORCEADD DNS..2
(3405 4070);
PAINT RED (3405 4070);
FORCEPROP 2 LAST CDS_LIB mstr_misc
J 0
(3405 4070);
PAINT ORANGE (3405 4070);
DISPLAY INVISIBLE (3405 4070);
FORCEPROP 1 LAST COMMENT_BODY TRUE
R 1
J 0
(3480 3845);
DISPLAY 0.872340 (3480 3845);
PAINT GREEN (3480 3845);
DISPLAY INVISIBLE (3480 3845);
FORCEADD DNS..2
(-1720 1570);
PAINT RED (-1720 1570);
FORCEPROP 2 LAST CDS_LIB mstr_misc
J 0
(-1720 1570);
PAINT ORANGE (-1720 1570);
DISPLAY INVISIBLE (-1720 1570);
FORCEPROP 1 LAST COMMENT_BODY TRUE
R 1
J 0
(-1645 1345);
DISPLAY 0.872340 (-1645 1345);
PAINT GREEN (-1645 1345);
DISPLAY INVISIBLE (-1645 1345);
WIRE 16 -1 (-500 875)(-500 1050);
WIRE 16 -1 (-650 1050)(-500 1050);
WIRE 16 -1 (-500 2475)(-500 2250);
WIRE 16 -1 (-650 2250)(-500 2250);
WIRE 16 -1 (3400 3925)(3400 3975);
WIRE 16 -1 (2200 2975)(2200 2900);
WIRE 16 -1 (2275 3850)(2275 3800);
WIRE 16 -1 (275 3325)(275 3225);
WIRE 16 -1 (550 1125)(550 1000);
WIRE 16 -1 (250 1125)(250 1000);
WIRE 16 -1 (850 1125)(850 1000);
WIRE 16 -1 (1150 1125)(1150 1000);
WIRE 16 -1 (2500 1125)(2500 1000);
WIRE 16 -1 (2200 1125)(2200 1000);
WIRE 16 -1 (1900 1125)(1900 1000);
WIRE 16 -1 (1600 1125)(1600 1000);
WIRE 16 -1 (2950 1125)(2950 1000);
WIRE 16 -1 (3850 1125)(3850 1000);
WIRE 16 -1 (3550 1125)(3550 1000);
WIRE 16 -1 (3250 1125)(3250 1000);
WIRE 16 -1 (3850 1600)(3850 1450);
WIRE 16 -1 (3550 1450)(3850 1450);
WIRE 16 -1 (3850 1275)(3850 1450);
WIRE 16 -1 (3250 1450)(3550 1450);
WIRE 16 -1 (3550 1450)(3550 1275);
WIRE 16 -1 (2950 1450)(3250 1450);
WIRE 16 -1 (3250 1450)(3250 1275);
WIRE 16 -1 (2500 1450)(2950 1450);
WIRE 16 -1 (2950 1275)(2950 1450);
WIRE 16 -1 (2200 1450)(2500 1450);
WIRE 16 -1 (2500 1450)(2500 1275);
WIRE 16 -1 (1900 1450)(2200 1450);
WIRE 16 -1 (2200 1450)(2200 1275);
WIRE 16 -1 (1600 1450)(1900 1450);
WIRE 16 -1 (1900 1450)(1900 1275);
WIRE 16 -1 (1600 1450)(1150 1450);
WIRE 16 -1 (1600 1275)(1600 1450);
WIRE 16 -1 (1150 1450)(850 1450);
WIRE 16 -1 (1150 1450)(1150 1275);
WIRE 16 -1 (850 1450)(550 1450);
WIRE 16 -1 (850 1450)(850 1275);
WIRE 16 -1 (550 1450)(250 1450);
WIRE 16 -1 (550 1450)(550 1275);
WIRE 16 -1 (250 1275)(250 1450);
WIRE 16 -1 (2100 2550)(2100 2500);
WIRE 16 -1 (2100 2500)(2650 2500);
WIRE 16 -1 (2100 2400)(2100 2500);
WIRE 16 -1 (3200 2500)(2650 2500);
WIRE 16 -1 (2650 2400)(2650 2500);
WIRE 16 -1 (3200 2400)(3200 2500);
WIRE 16 -1 (2100 2025)(2100 2050);
WIRE 16 -1 (2650 2050)(2100 2050);
WIRE 16 -1 (2100 2200)(2100 2050);
WIRE 16 -1 (3200 2050)(2650 2050);
WIRE 16 -1 (2650 2200)(2650 2050);
WIRE 16 -1 (3200 2200)(3200 2050);
WIRE 16 -1 (3975 3675)(3975 3625);
WIRE 16 -1 (3975 3625)(3650 3625);
WIRE 16 -1 (3975 3625)(3975 3525);
WIRE 16 -1 (3350 3625)(3650 3625);
WIRE 16 -1 (3650 3550)(3650 3625);
WIRE 16 -1 (3250 3625)(3350 3625);
WIRE 16 -1 (3350 3525)(3350 3625);
WIRE 16 -1 (3250 2850)(3250 3625);
WIRE 16 -1 (3150 3625)(3250 3625);
WIRE 16 -1 (475 2850)(3250 2850);
WIRE 16 -1 (475 4075)(475 2850);
WIRE 16 -1 (575 4075)(475 4075);
WIRE 16 -1 (3975 3200)(3975 3225);
WIRE 16 -1 (3975 3225)(3650 3225);
WIRE 16 -1 (3975 3325)(3975 3225);
WIRE 16 -1 (3350 3225)(3650 3225);
WIRE 16 -1 (3650 3350)(3650 3225);
WIRE 16 -1 (3350 3225)(3350 3325);
WIRE 16 -1 (1725 3300)(1725 3375);
WIRE 16 -1 (1725 3375)(1725 3425);
WIRE 16 -1 (1725 3375)(1575 3375);
WIRE 16 -1 (1725 3425)(1725 3475);
WIRE 16 -1 (1725 3425)(1575 3425);
WIRE 16 -1 (1725 3475)(1725 3525);
WIRE 16 -1 (1725 3475)(1575 3475);
WIRE 16 -1 (1575 3525)(1725 3525);
WIRE 16 -1 (-3100 3875)(-3100 3925);
WIRE 16 -1 (-2800 3925)(-3100 3925);
WIRE 16 -1 (-3100 4050)(-3100 3925);
WIRE 16 -1 (-2800 3925)(-2525 3925);
WIRE 16 -1 (-2800 4050)(-2800 3925);
WIRE 16 -1 (-2250 3925)(-2525 3925);
WIRE 16 -1 (-2525 4050)(-2525 3925);
WIRE 16 -1 (-1975 3925)(-2250 3925);
WIRE 16 -1 (-2250 4050)(-2250 3925);
WIRE 16 -1 (-1700 3925)(-1975 3925);
WIRE 16 -1 (-1975 4050)(-1975 3925);
WIRE 16 -1 (-1700 3925)(-1350 3925);
WIRE 16 -1 (-1700 4050)(-1700 3925);
WIRE 16 -1 (-950 3925)(-1350 3925);
WIRE 16 -1 (-1350 4100)(-1350 3925);
WIRE 16 -1 (-950 4100)(-950 3925);
WIRE 16 -1 (-675 4750)(-675 4800);
WIRE 16 -1 (-675 4750)(-675 4275);
WIRE 16 -1 (-675 4750)(-950 4750);
WIRE 16 -1 (-950 4750)(-1350 4750);
WIRE 16 -1 (-950 4300)(-950 4750);
WIRE 16 -1 (-675 4275)(500 4275);
WIRE 16 -1 (500 4175)(500 4275);
WIRE 16 -1 (500 4275)(575 4275);
WIRE 16 -1 (-1350 4250)(-1350 4750);
WIRE 16 -1 (-1350 4750)(-1475 4750);
WIRE 16 -1 (575 4175)(500 4175);
WIRE 16 -1 (-3100 4500)(-3100 4425);
WIRE 16 -1 (-2800 4425)(-3100 4425);
WIRE 16 -1 (-3100 4250)(-3100 4425);
WIRE 16 -1 (-2800 4425)(-2525 4425);
WIRE 16 -1 (-2800 4250)(-2800 4425);
WIRE 16 -1 (-2250 4425)(-2525 4425);
WIRE 16 -1 (-2525 4250)(-2525 4425);
WIRE 16 -1 (-1975 4425)(-2250 4425);
WIRE 16 -1 (-2250 4250)(-2250 4425);
WIRE 16 -1 (350 4425)(-1975 4425);
WIRE 16 -1 (-1975 4250)(-1975 4425);
WIRE 16 -1 (350 4425)(350 4375);
WIRE 16 -1 (575 4425)(350 4425);
WIRE 16 -1 (575 4375)(350 4375);
WIRE 16 2175 (-1925 3375)(-925 3375);
WIRE 16 2175 (-925 3775)(-925 3375);
WIRE 16 2175 (-1925 3775)(-1925 3375);
WIRE 16 2175 (-1925 3775)(-925 3775);
WIRE 16 682 (-1775 1850)(-2675 1850);
WIRE 16 682 (-1775 2575)(-1775 1850);
WIRE 16 682 (-2675 1850)(-2675 2575);
WIRE 16 682 (-2675 2575)(-1775 2575);
WIRE 16 -1 (-1700 4750)(-1675 4750);
WIRE 16 -1 (-1700 4250)(-1700 4475);
WIRE 16 -1 (-1700 4475)(-1700 4750);
WIRE 16 -1 (-1700 4475)(575 4475);
FORCEPROP 2 LAST SIG_NAME VR_PVCCIO_CPU1_PH1_VCIN
J 0
(-260 4485);
DISPLAY 0.617021 (-260 4485);
PAINT ORANGE (-260 4485);
FORCEPROP 2 LASTPROP $XRERR UNIQUE?
J 0
(-500 4485);
DISPLAY 0.638298 (-500 4485);
PAINT MONO (-500 4485);
DISPLAY INVISIBLE (-500 4485);
WIRE 16 -1 (575 3975)(-325 3975);
FORCEPROP 0 LAST SIG_NAME TP_PVCCIO_CPU1_GL_1
J 0
(-310 3985);
DISPLAY 0.617021 (-310 3985);
PAINT ORANGE (-310 3985);
FORCEPROP 2 LASTPROP $XRERR UNIQUE?
J 0
(-565 3975);
DISPLAY 0.638298 (-565 3975);
PAINT MONO (-565 3975);
DISPLAY INVISIBLE (-565 3975);
WIRE 16 -1 (275 3525)(275 3725);
WIRE 16 -1 (575 3725)(275 3725);
WIRE 16 -1 (275 3725)(275 4825);
WIRE 16 -1 (275 4825)(2800 4825);
FORCEPROP 2 LAST SIG_NAME VR_PVCCIO_CPU1_AIREF1
J 0
(1445 4829);
DISPLAY 0.617021 (1445 4829);
PAINT ORANGE (1445 4829);
WIRE 16 -1 (2200 3550)(2200 3625);
WIRE 16 -1 (2850 3625)(2200 3625);
WIRE 16 -1 (1575 3625)(2200 3625);
FORCEPROP 2 LAST SIG_NAME VR_PVCCIO_CPU1_PH1_SW
J 0
(1640 3635);
DISPLAY 0.617021 (1640 3635);
PAINT ORANGE (1640 3635);
FORCEPROP 2 LASTPROP $XRERR UNIQUE?
J 0
(1400 3635);
DISPLAY 0.638298 (1400 3635);
PAINT MONO (1400 3635);
DISPLAY INVISIBLE (1400 3635);
WIRE 16 -1 (-2275 3825)(575 3825);
FORCEPROP 2 LAST SIG_NAME VR_PVCCIO_CPU1_PWM1
J 0
(-2250 3849);
DISPLAY 0.617021 (-2250 3849);
PAINT ORANGE (-2250 3849);
WIRE 16 -1 (1575 4475)(2825 4475);
FORCEPROP 2 LAST SIG_NAME ISENSE_PVCCIO_CPU1_PH1_IMON
J 2
(2600 4489);
DISPLAY 0.617021 (2600 4489);
PAINT ORANGE (2600 4489);
WIRE 16 -1 (2275 4050)(2275 4125);
WIRE 16 -1 (2275 4125)(2675 4125);
WIRE 16 -1 (1575 4125)(1575 3975);
WIRE 16 -1 (1575 4125)(2275 4125);
FORCEPROP 2 LAST SIG_NAME A_TSENSE_PVCCIO_CPU1
J 2
(2025 4139);
DISPLAY 0.617021 (2025 4139);
PAINT ORANGE (2025 4139);
WIRE 3 682 (1650 4225)(1750 4225);
WIRE 16 -1 (575 3925)(-350 3925);
FORCEPROP 0 LAST SIG_NAME TP_PVCCIO_CPU1_GL_0
J 0
(-335 3935);
DISPLAY 0.617021 (-335 3935);
PAINT ORANGE (-335 3935);
FORCEPROP 2 LASTPROP $XRERR UNIQUE?
J 0
(-590 3925);
DISPLAY 0.638298 (-590 3925);
PAINT MONO (-590 3925);
DISPLAY INVISIBLE (-590 3925);
WIRE 16 -1 (3400 4175)(3400 4275);
WIRE 16 -1 (1575 4275)(3400 4275);
FORCEPROP 0 LAST SIG_NAME VR_PVCCIO_CPU1_OCSET
J 0
(1715 4285);
DISPLAY 0.617021 (1715 4285);
PAINT ORANGE (1715 4285);
FORCEPROP 2 LASTPROP $XRERR UNIQUE?
J 0
(1475 4285);
DISPLAY 0.638298 (1475 4285);
PAINT MONO (1475 4285);
DISPLAY INVISIBLE (1475 4285);
WIRE 3 2175 (2050 3700)(2575 3700);
WIRE 3 2175 (2575 4175)(2575 3700);
WIRE 3 2175 (2050 4175)(2050 3700);
WIRE 3 2175 (2050 4175)(2575 4175);
WIRE 3 2175 (-50 3150)(675 3150);
WIRE 3 2175 (675 3675)(675 3150);
WIRE 3 2175 (-50 3675)(-50 3150);
WIRE 3 2175 (-50 3675)(675 3675);
WIRE 3 2175 (-825 3525)(-550 3525);
WIRE 3 2175 (-550 3800)(-550 3525);
WIRE 3 2175 (-825 3800)(-825 3525);
WIRE 3 2175 (-825 3800)(-550 3800);
WIRE 16 -1 (25 3575)(575 3575);
WIRE 16 -1 (25 3425)(25 3575);
WIRE 16 -1 (-1625 3425)(-1625 3475);
WIRE 16 -1 (-1625 3425)(25 3425);
FORCEPROP 2 LAST SIG_NAME VR_PVCCIO_CPU1_PH1_PHASE
J 0
(-1610 3435);
DISPLAY 0.617021 (-1610 3435);
PAINT ORANGE (-1610 3435);
FORCEPROP 2 LASTPROP $XRERR UNIQUE?
J 0
(-1850 3435);
DISPLAY 0.638298 (-1850 3435);
PAINT MONO (-1850 3435);
DISPLAY INVISIBLE (-1850 3435);
WIRE 16 -1 (-1625 3700)(-1625 3675);
WIRE 16 -1 (-775 3700)(-1625 3700);
FORCEPROP 0 LAST SIG_NAME VR_PVCCIO_CPU1_PH1_BOOT
J 0
(-1610 3710);
DISPLAY 0.617021 (-1610 3710);
PAINT ORANGE (-1610 3710);
FORCEPROP 2 LASTPROP $XRERR UNIQUE?
J 0
(-1850 3710);
DISPLAY 0.638298 (-1850 3710);
PAINT MONO (-1850 3710);
DISPLAY INVISIBLE (-1850 3710);
WIRE 16 -1 (25 3625)(575 3625);
WIRE 16 -1 (25 3700)(25 3625);
WIRE 16 -1 (-575 3700)(25 3700);
FORCEPROP 0 LAST SIG_NAME VR_PVCCIO_CPU1_PH1_BOOT_R
J 0
(-510 3710);
DISPLAY 0.617021 (-510 3710);
PAINT ORANGE (-510 3710);
FORCEPROP 2 LASTPROP $XRERR UNIQUE?
J 0
(-750 3710);
DISPLAY 0.638298 (-750 3710);
PAINT MONO (-750 3710);
DISPLAY INVISIBLE (-750 3710);
WIRE 16 -1 (2200 3275)(2200 3350);
WIRE 16 -1 (2200 3275)(2975 3275);
WIRE 16 -1 (2200 3225)(2200 3275);
FORCEPROP 2 LAST SIG_NAME VR_PVCCIO_CPU1_PH1_SW_RC
J 0
(2240 3285);
DISPLAY 0.510638 (2240 3285);
PAINT ORANGE (2240 3285);
FORCEPROP 2 LASTPROP $XRERR UNIQUE?
J 0
(3005 3275);
DISPLAY 0.638298 (3005 3275);
PAINT MONO (3005 3275);
DISPLAY INVISIBLE (3005 3275);
WIRE 16 2175 (-1925 1750)(-2250 1750);
WIRE 16 2175 (-1925 1300)(-1925 1750);
WIRE 16 2175 (-2250 1750)(-2250 1300);
WIRE 16 2175 (-2250 1300)(-1925 1300);
WIRE 16 -1 (-1725 1675)(-1725 1750);
WIRE 16 -1 (-1725 1750)(-1400 1750);
WIRE 16 -1 (-1875 1750)(-1725 1750);
WIRE 16 -1 (-1875 1550)(-1875 1750);
WIRE 16 -1 (-2275 1550)(-1875 1550);
WIRE 16 -1 (-2275 1750)(-3000 1750);
FORCEPROP 2 LAST SIG_NAME VSENSE_PVCCIO_CPU1_SKT_VSEN
J 0
(-3004 1758);
DISPLAY 0.617021 (-3004 1758);
PAINT ORANGE (-3004 1758);
WIRE 16 -1 (-2275 1750)(-2275 1550);
WIRE 16 -1 (-1725 1475)(-1725 1300);
WIRE 16 -1 (-1400 1300)(-1725 1300);
WIRE 16 -1 (-1875 1300)(-1725 1300);
WIRE 16 -1 (-1875 1500)(-1875 1300);
WIRE 16 -1 (-2275 1500)(-1875 1500);
WIRE 16 -1 (-2275 1300)(-2275 1500);
WIRE 16 -1 (-3000 1300)(-2275 1300);
FORCEPROP 2 LAST SIG_NAME VSENSE_PVCCIO_CPU1_SKT_VRTN
J 0
(-3003 1325);
DISPLAY 0.617021 (-3003 1325);
PAINT ORANGE (-3003 1325);
WIRE 16 2175 (-1450 1900)(-1450 1050);
WIRE 16 2175 (-1050 1900)(-1450 1900);
WIRE 16 2175 (-1450 1050)(-1050 1050);
WIRE 16 2175 (-1050 1050)(-1050 1900);
WIRE 16 -1 (-850 2250)(-1000 2250);
WIRE 16 -1 (-1000 1750)(-1100 1750);
WIRE 16 -1 (-1000 2250)(-1000 1750);
WIRE 16 -1 (-350 1750)(-1000 1750);
FORCEPROP 2 LAST SIG_NAME VSENSE_PVCCIO_CPU1_AVSP
J 0
(-975 1763);
DISPLAY 0.617021 (-975 1763);
PAINT ORANGE (-975 1763);
WIRE 16 -1 (-850 1050)(-1000 1050);
WIRE 16 -1 (-1100 1300)(-1000 1300);
WIRE 16 -1 (-1000 1050)(-1000 1300);
WIRE 16 -1 (-325 1300)(-1000 1300);
FORCEPROP 2 LAST SIG_NAME VSENSE_PVCCIO_CPU1_AVSN
J 0
(-988 1313);
DISPLAY 0.617021 (-988 1313);
PAINT ORANGE (-988 1313);
WIRE 68 -1 (150 1500)(1450 1500);
WIRE 68 -1 (1450 900)(1450 1500);
WIRE 68 -1 (150 900)(150 1500);
WIRE 68 -1 (150 900)(1450 900);
WIRE 3 2175 (-1750 4600)(-1400 4600);
WIRE 3 2175 (-1400 4850)(-1400 4600);
WIRE 3 2175 (-1750 4850)(-1750 4600);
WIRE 3 2175 (-1750 4850)(-1400 4850);
WIRE 3 682 (-1300 4325)(-1300 4025);
WIRE 3 682 (-1400 4325)(-1300 4325);
WIRE 3 682 (-1300 4025)(-1400 4025);
WIRE 3 682 (-1400 4025)(-1400 4325);
WIRE 16 2175 (-1425 3975)(-725 3975);
WIRE 16 2175 (-725 4375)(-725 3975);
WIRE 16 2175 (-1425 4375)(-1425 3975);
WIRE 16 2175 (-1425 4375)(-725 4375);
WIRE 3 2175 (2100 2925)(2725 2925);
WIRE 3 2175 (2725 3675)(2725 2925);
WIRE 3 2175 (2100 3675)(2100 2925);
WIRE 3 2175 (2100 3675)(2725 3675);
WIRE 3 2175 (100 850)(4200 850);
WIRE 3 2175 (4200 1550)(4200 850);
WIRE 3 2175 (100 1550)(100 850);
WIRE 3 2175 (100 1550)(4200 1550);
WIRE 68 -1 (2850 900)(4150 900);
WIRE 68 -1 (4150 900)(4150 1500);
WIRE 68 -1 (2850 900)(2850 1500);
WIRE 68 -1 (2850 1500)(4150 1500);
WIRE 68 -1 (1500 900)(2800 900);
WIRE 68 -1 (2800 900)(2800 1500);
WIRE 68 -1 (1500 900)(1500 1500);
WIRE 68 -1 (1500 1500)(2800 1500);
DOT 1 (2650 2500);
DOT 1 (2100 2050);
DOT 1 (2100 2500);
DOT 1 (-1350 3925);
DOT 1 (-1350 4750);
DOT 1 (-1700 4475);
DOT 1 (-1000 1300);
DOT 1 (-1000 1750);
DOT 1 (1600 1450);
DOT 1 (1900 1450);
DOT 1 (2500 1450);
DOT 1 (2200 1450);
DOT 1 (2950 1450);
DOT 1 (3250 1450);
DOT 1 (3550 1450);
DOT 1 (3850 1450);
DOT 1 (1725 3425);
DOT 1 (2200 3625);
DOT 1 (-1725 1300);
DOT 1 (-1725 1750);
DOT 1 (2275 4125);
DOT 1 (1725 3475);
DOT 1 (500 4275);
DOT 1 (350 4425);
DOT 1 (275 3725);
DOT 1 (-1700 3925);
DOT 1 (-1975 4425);
DOT 1 (-1975 3925);
DOT 1 (-2250 4425);
DOT 1 (-2250 3925);
DOT 1 (-2525 4425);
DOT 1 (-2525 3925);
DOT 1 (-2800 4425);
DOT 1 (-2800 3925);
DOT 1 (-3100 3925);
DOT 1 (-3100 4425);
DOT 1 (1725 3375);
DOT 1 (2200 3275);
DOT 1 (3975 3225);
DOT 1 (-950 4750);
DOT 1 (-675 4750);
DOT 1 (3250 3625);
DOT 1 (1150 1450);
DOT 1 (850 1450);
DOT 1 (550 1450);
DOT 1 (3975 3625);
DOT 1 (3350 3625);
DOT 1 (3650 3625);
DOT 1 (3650 3225);
DOT 1 (2650 2050);
FORCENOTE
TP FAB1 CHANGE RES TO 1 OHM 0603 0107
(2075 2775) 0;
DISPLAY LEFT (2075 2775);
DISPLAY 0.808511 (2075 2775);
PAINT RED (2075 2775);
FORCENOTE
VOUT=1.0V (TYP) SVID
(-2650 2325) 0;
DISPLAY LEFT (-2650 2325);
DISPLAY 0.808511 (-2650 2325);
PAINT PURPLE (-2650 2325);
FORCENOTE
TOTAL TOL = 1.057VMAX/0.937VMIN
(-2650 2175) 0;
DISPLAY LEFT (-2650 2175);
DISPLAY 0.808511 (-2650 2175);
PAINT PURPLE (-2650 2175);
FORCENOTE
IOUT STEP=14APP
(-2650 2025) 0;
DISPLAY LEFT (-2650 2025);
DISPLAY 0.808511 (-2650 2025);
PAINT PURPLE (-2650 2025);
FORCENOTE
IOUT PK= 21.44A
(-2650 2075) 0;
DISPLAY LEFT (-2650 2075);
DISPLAY 0.808511 (-2650 2075);
PAINT PURPLE (-2650 2075);
FORCENOTE
IOUT TDC=14.44A
(-2650 2125) 0;
DISPLAY LEFT (-2650 2125);
DISPLAY 0.808511 (-2650 2125);
PAINT PURPLE (-2650 2125);
FORCENOTE
DC TOL = +/-5MV
(-2650 2225) 0;
DISPLAY LEFT (-2650 2225);
DISPLAY 0.808511 (-2650 2225);
PAINT PURPLE (-2650 2225);
FORCENOTE
RIPPLE = +/- 10MV
(-2650 2275) 0;
DISPLAY LEFT (-2650 2275);
DISPLAY 0.808511 (-2650 2275);
PAINT PURPLE (-2650 2275);
FORCENOTE
ROOM= PVCCIO_CPU1
(-1648 3056) 0;
DISPLAY LEFT (-1648 3056);
DISPLAY 1.595745 (-1648 3056);
PAINT PURPLE (-1648 3056);
FORCENOTE
TDA21460
(900 4550) 0;
DISPLAY LEFT (900 4550);
DISPLAY 1.021277 (900 4550);
PAINT SKYBLUE (900 4550);
FORCENOTE
TP FAB1 ADD NET NAME 12/04
(2575 3225) 0;
DISPLAY LEFT (2575 3225);
DISPLAY 0.638298 (2575 3225);
PAINT RED (2575 3225);
FORCENOTE
TP FAB1 CHANGE PN 0310
(-1425 4375) 0;
DISPLAY LEFT (-1425 4375);
DISPLAY 1.021277 (-1425 4375);
PAINT RED (-1425 4375);
FORCENOTE
PLACE ON TOP
(-1480 3850) 0;
DISPLAY LEFT (-1480 3850);
DISPLAY 1.553191 (-1480 3850);
PAINT PURPLE (-1480 3850);
FORCENOTE
SPOF
(-1409 1925) 0;
DISPLAY LEFT (-1409 1925);
DISPLAY 1.340426 (-1409 1925);
PAINT PURPLE (-1409 1925);
FORCENOTE
ROUTE AS DIFF PAIR
(-2503 1174) 0;
DISPLAY LEFT (-2503 1174);
DISPLAY 1.021277 (-2503 1174);
PAINT PURPLE (-2503 1174);
FORCENOTE
PUT TOGETHER
(1600 1500) 0;
DISPLAY LEFT (1600 1500);
DISPLAY 0.808511 (1600 1500);
PAINT PURPLE (1600 1500);
FORCENOTE
PUT TOGETHER
(2875 1500) 0;
DISPLAY LEFT (2875 1500);
DISPLAY 0.808511 (2875 1500);
PAINT PURPLE (2875 1500);
FORCENOTE
TP FAB1 CHANGE TO 0 OHM 0107
(-1725 4850) 0;
DISPLAY LEFT (-1725 4850);
DISPLAY 0.638298 (-1725 4850);
PAINT RED (-1725 4850);
FORCENOTE
BOM_COST = PROC_VRD_PVCCIO_CPU1
(-3675 400) 0;
DISPLAY LEFT (-3675 400);
DISPLAY 1.021277 (-3675 400);
PAINT PURPLE (-3675 400);
FORCENOTE
ROOM = PVCCIO_CPU1
(-3675 475) 0;
DISPLAY LEFT (-3675 475);
DISPLAY 1.021277 (-3675 475);
PAINT PURPLE (-3675 475);
FORCENOTE
SOCKET SIDE
(-3093 1526) 0;
DISPLAY LEFT (-3093 1526);
DISPLAY 1.021277 (-3093 1526);
PAINT PURPLE (-3093 1526);
FORCENOTE
5MIL SPACING
(-2513 1034) 0;
DISPLAY LEFT (-2513 1034);
DISPLAY 1.021277 (-2513 1034);
PAINT PURPLE (-2513 1034);
FORCENOTE
5MIL WIDTH
(-2513 1109) 0;
DISPLAY LEFT (-2513 1109);
DISPLAY 1.021277 (-2513 1109);
PAINT PURPLE (-2513 1109);
FORCENOTE
VBOOT=1.0V 
(-2650 1875) 0;
DISPLAY LEFT (-2650 1875);
DISPLAY 0.808511 (-2650 1875);
PAINT PURPLE (-2650 1875);
FORCENOTE
TP FAB1 CO-LAY WITH TI PARTS 11/16
(2300 4175) 0;
DISPLAY LEFT (2300 4175);
DISPLAY 0.851064 (2300 4175);
PAINT RED (2300 4175);
FORCENOTE
TP FAB1 DEL NET 0309
(1800 4225) 0;
DISPLAY LEFT (1800 4225);
DISPLAY 1.021277 (1800 4225);
PAINT RED (1800 4225);
FORCENOTE
SW FREQ=641 KHZ 
(-2650 1925) 0;
DISPLAY LEFT (-2650 1925);
DISPLAY 0.808511 (-2650 1925);
PAINT PURPLE (-2650 1925);
FORCENOTE
IOUT DI/DT =22 A/US
(-2650 1975) 0;
DISPLAY LEFT (-2650 1975);
DISPLAY 0.808511 (-2650 1975);
PAINT PURPLE (-2650 1975);
FORCENOTE
SPOF
(-1479 3226) 0;
DISPLAY LEFT (-1479 3226);
DISPLAY 2.340426 (-1479 3226);
PAINT PURPLE (-1479 3226);
FORCENOTE
TP FAB1 CO-LAY WITH TI PARTS 11/16
(-975 3300) 0;
DISPLAY LEFT (-975 3300);
DISPLAY 0.851064 (-975 3300);
PAINT RED (-975 3300);
FORCENOTE
TP FAB1 CHANGE L4E2 PN 0122
(2625 3800) 0;
DISPLAY LEFT (2625 3800);
DISPLAY 1.021277 (2625 3800);
PAINT RED (2625 3800);
FORCENOTE
TP FAB1 CHANGE ONE 100UF CPA TO FOUR 22UF CAPS 0107
(625 750) 0;
DISPLAY LEFT (625 750);
DISPLAY 1.021277 (625 750);
PAINT RED (625 750);
FORCENOTE
PUT TOGETHER
(150 1500) 0;
DISPLAY LEFT (150 1500);
DISPLAY 0.808511 (150 1500);
PAINT PURPLE (150 1500);
FORCENOTE
VR CONTROLLER SIDE
(-875 1498) 0;
DISPLAY LEFT (-875 1498);
DISPLAY 1.021277 (-875 1498);
PAINT PURPLE (-875 1498);
FORCENOTE
TP FAB1 CO-LAY WITH TI PARTS 11/16
(2075 2700) 0;
DISPLAY LEFT (2075 2700);
DISPLAY 0.851064 (2075 2700);
PAINT RED (2075 2700);
QUIT
